# Altium SchDoc records: 01-USER_IO.SchDoc
|HEADER=Protel for Windows - Schematic Capture Binary File Version 5.0|Weight=1518|MinorVersion=7
|RECORD=31|FontIdCount=8|Size1=10|FontName1=Times New Roman|Size2=10|Rotation2=90|FontName2=Times New Roman|Size3=10|Underline3=T|FontName3=Times New Roman|Size4=8|FontName4=Arial|Size5=10|FontName5=Arial|Size6=12|Underline6=T|FontName6=Arial|Size7=11|FontName7=Arial|Size8=24|FontName8=Times New Roman|UseMBCS=T|IsBOC=T|HotSpotGridOn=T|HotSpotGridSize=5|SheetStyle=12|SystemFont=5|BorderOn=T|SheetNumberSpaceSize=12|AreaColor=16317695|SnapGridOn=T|SnapGridSize=10|VisibleGridOn=T|VisibleGridSize=10|CustomX=2338|CustomX_Frac=58268|CustomY=1653|CustomY_Frac=54331|CustomXZones=8|CustomYZones=6|CustomMarginWidth=19|CustomMarginWidth_Frac=80000|ShowTemplateGraphics=T|TemplateFileName=C:\Users\<user>\Documents\Altium\AD20\Templates\Timecard.SchDot|Display_Unit=0
|RECORD=39|IsNotAccesible=T|OwnerPartId=-1|FileName=C:\Users\<user>\Documents\Altium\AD20\Templates\Timecard.SchDot
|RECORD=4|OwnerIndex=1|OwnerPartId=-1|Location.X=1594|Location.Y=39|Color=8388608|FontID=6|Text=timingcard.com|URL=http://timingcard.com
|RECORD=6|OwnerIndex=1|IndexInSheet=1|OwnerPartId=-1|LocationCount=2|X1=1680|Y1=35|X2=1576|Y2=35
|RECORD=4|OwnerIndex=1|IndexInSheet=2|OwnerPartId=-1|Location.X=1615|Location.Y=27|Justification=4|Color=16711680|FontID=7|Text==SheetNumber
|RECORD=4|OwnerIndex=1|IndexInSheet=3|OwnerPartId=-1|Location.X=1581|Location.X_Frac=42446|Location.Y=29|Location.Y_Frac=96838|Justification=3|FontID=4|Text=SHEET
|RECORD=4|OwnerIndex=1|IndexInSheet=4|OwnerPartId=-1|Location.X=1639|Location.X_Frac=42446|Location.Y=29|Location.Y_Frac=96838|Justification=3|FontID=4|Text=OF
|RECORD=6|OwnerIndex=1|IndexInSheet=5|OwnerPartId=-1|LineWidth=1|LocationCount=2|X1=1679|X1_Frac=42446|Y1=117|Y1_Frac=96838|X2=1576|Y2=118
|RECORD=4|OwnerIndex=1|IndexInSheet=6|OwnerPartId=-1|Location.X=1659|Location.Y=27|Justification=4|Color=16711680|FontID=7|Text==SheetTotal
|RECORD=30|OwnerIndex=1|IndexInSheet=7|OwnerPartId=-1|Location.X=1578|Location.Y=65|Corner.X=1673|Corner.X_Frac=88801|Corner.Y=115|KeepAspect=T|FileName=C:\Users\<user>\Desktop\Timecard Logo\TIMECARD.jpg
|RECORD=6|OwnerIndex=1|IndexInSheet=8|OwnerPartId=-1|LineWidth=1|LocationCount=2|X1=1576|X1_Frac=3162|Y1=117|Y1_Frac=42446|X2=1576|Y2=21
|RECORD=6|OwnerIndex=1|IndexInSheet=9|OwnerPartId=-1|LocationCount=2|X1=1680|Y1=51|X2=1576|Y2=51
|RECORD=4|OwnerIndex=1|IndexInSheet=10|OwnerPartId=-1|Location.X=1581|Location.X_Frac=42446|Location.Y=56|Location.Y_Frac=96838|Justification=3|FontID=4|Text=REV
|RECORD=4|OwnerIndex=1|IndexInSheet=11|OwnerPartId=-1|Location.X=1619|Location.Y=57|Justification=3|FontID=4|Text=DATE
|RECORD=6|OwnerIndex=1|IndexInSheet=12|OwnerPartId=-1|LocationCount=2|X1=1680|Y1=65|X2=1576|Y2=65
|RECORD=4|OwnerIndex=1|IndexInSheet=13|OwnerPartId=-1|Location.X=1605|Location.Y=58|Justification=4|Color=16711680|FontID=7|Text==ProjectRevision
|RECORD=4|OwnerIndex=1|IndexInSheet=14|OwnerPartId=-1|Location.X=1659|Location.Y=58|Justification=4|Color=16711680|FontID=7|Text==ProjectDate
|RECORD=41|IndexInSheet=1|OwnerPartId=-1|Color=8388608|FontID=1|IsHidden=T|Text=*|Name=CurrentTime|ReadOnlyState=1
|RECORD=41|IndexInSheet=2|OwnerPartId=-1|Color=8388608|FontID=1|IsHidden=T|Text=*|Name=CurrentDate|ReadOnlyState=1
|RECORD=41|IndexInSheet=3|OwnerPartId=-1|Color=8388608|FontID=1|IsHidden=T|Text=*|Name=Time|ReadOnlyState=1
|RECORD=41|IndexInSheet=4|OwnerPartId=-1|Color=8388608|FontID=1|IsHidden=T|Text=*|Name=Date|ReadOnlyState=1
|RECORD=41|IndexInSheet=5|OwnerPartId=-1|Color=8388608|FontID=1|IsHidden=T|Text=*|Name=DocumentFullPathAndName|ReadOnlyState=1
|RECORD=41|IndexInSheet=6|OwnerPartId=-1|Color=8388608|FontID=1|IsHidden=T|Text=*|Name=DocumentName|ReadOnlyState=1
|RECORD=41|IndexInSheet=7|OwnerPartId=-1|Color=8388608|FontID=1|IsHidden=T|Text=*|Name=ModifiedDate|ReadOnlyState=1
|RECORD=41|IndexInSheet=8|OwnerPartId=-1|Color=8388608|FontID=1|IsHidden=T|Text=*|Name=ApprovedBy|ReadOnlyState=1
|RECORD=41|IndexInSheet=9|OwnerPartId=-1|Color=8388608|FontID=1|IsHidden=T|Text=*|Name=CheckedBy|ReadOnlyState=1
|RECORD=41|IndexInSheet=10|OwnerPartId=-1|Color=8388608|FontID=1|IsHidden=T|Text=*|Name=Author|ReadOnlyState=1
|RECORD=41|IndexInSheet=11|OwnerPartId=-1|Color=8388608|FontID=1|IsHidden=T|Text=*|Name=CompanyName|ReadOnlyState=1
|RECORD=41|IndexInSheet=12|OwnerPartId=-1|Color=8388608|FontID=1|IsHidden=T|Text=*|Name=DrawnBy|ReadOnlyState=1
|RECORD=41|IndexInSheet=13|OwnerPartId=-1|Color=8388608|FontID=1|IsHidden=T|Text=*|Name=Engineer|ReadOnlyState=1
|RECORD=41|IndexInSheet=14|OwnerPartId=-1|Color=8388608|FontID=1|IsHidden=T|Text=*|Name=Organization|ReadOnlyState=1
|RECORD=41|IndexInSheet=15|OwnerPartId=-1|Color=8388608|FontID=1|IsHidden=T|Text=*|Name=Address1|ReadOnlyState=1
|RECORD=41|IndexInSheet=16|OwnerPartId=-1|Color=8388608|FontID=1|IsHidden=T|Text=*|Name=Address2|ReadOnlyState=1
|RECORD=41|IndexInSheet=17|OwnerPartId=-1|Color=8388608|FontID=1|IsHidden=T|Text=*|Name=Address3|ReadOnlyState=1
|RECORD=41|IndexInSheet=18|OwnerPartId=-1|Color=8388608|FontID=1|IsHidden=T|Text=*|Name=Address4|ReadOnlyState=1
|RECORD=41|IndexInSheet=19|OwnerPartId=-1|Color=8388608|FontID=1|IsHidden=T|Text=*|Name=Title|ReadOnlyState=1
|RECORD=41|IndexInSheet=20|OwnerPartId=-1|Color=8388608|FontID=1|IsHidden=T|Text=1|Name=DocumentNumber|ReadOnlyState=1
|RECORD=41|IndexInSheet=21|OwnerPartId=-1|Color=8388608|FontID=1|IsHidden=T|Text=*|Name=Revision|ReadOnlyState=1
|RECORD=41|IndexInSheet=22|OwnerPartId=-1|Color=8388608|FontID=1|IsHidden=T|Text=1|Name=SheetNumber|ReadOnlyState=1
|RECORD=41|IndexInSheet=23|OwnerPartId=-1|Color=8388608|FontID=1|IsHidden=T|Text=7|Name=SheetTotal|ReadOnlyState=1
|RECORD=41|IndexInSheet=24|OwnerPartId=-1|Color=8388608|FontID=1|IsHidden=T|Text=*|Name=Rule|ReadOnlyState=1
|RECORD=41|IndexInSheet=25|OwnerPartId=-1|Color=8388608|FontID=1|IsHidden=T|Text=*|Name=ImagePath|ReadOnlyState=1
|RECORD=41|IndexInSheet=26|OwnerPartId=-1|Color=8388608|FontID=1|IsHidden=T|Text=*|Name=ProjectName|ReadOnlyState=1
|RECORD=41|IndexInSheet=27|OwnerPartId=-1|Color=8388608|FontID=1|IsHidden=T|Text=*|Name=Application_BuildNumber|ReadOnlyState=1
|RECORD=41|IndexInSheet=28|OwnerPartId=-1|Color=8388608|FontID=1|IsHidden=T|Name=ConfigurationParameters|ReadOnlyState=1
|RECORD=41|IndexInSheet=29|OwnerPartId=-1|Color=8388608|FontID=1|IsHidden=T|Name=ConfiguratorName|ReadOnlyState=1
|RECORD=41|IndexInSheet=30|OwnerPartId=-1|Color=8388608|FontID=1|IsHidden=T|Name=VersionControl_RevNumber|ReadOnlyState=1
|RECORD=41|IndexInSheet=31|OwnerPartId=-1|Color=8388608|FontID=1|IsHidden=T|Name=IsUserConfigurable|ReadOnlyState=1
|RECORD=41|IndexInSheet=32|OwnerPartId=-1|Color=8388608|FontID=1|IsHidden=T|Name=VersionControl_ProjFolderRevNumber|ReadOnlyState=1
|RECORD=41|IndexInSheet=33|OwnerPartId=-1|Color=8388608|FontID=1|IsHidden=T|Name=SPICEModelCache|ReadOnlyState=1
|RECORD=1|LibReference=NC7WV125K8X|ComponentDescription=Integrated Circuit|PartCount=2|DisplayModeCount=1|IndexInSheet=34|OwnerPartId=-1|Location.X=394|Location.Y=882|CurrentPartId=1|LibraryPath=*|SourceLibraryName=SamacSys.SchLib|TargetFileName=*|AreaColor=11599871|Color=128|PartIDLocked=T|DesignItemId=NC7WV125K8X|AllPinCount=8
|RECORD=41|OwnerIndex=50|OwnerPartId=-1|Location.X=394|Location.Y=882|Color=8388608|FontID=3|IsHidden=T|Text=https://www.mouser.com/datasheet/2/308/NC7WV125-1301459.pdf|Name=Datasheet Link
|RECORD=41|OwnerIndex=50|IndexInSheet=1|OwnerPartId=-1|Location.X=394|Location.Y=882|Color=8388608|FontID=1|IsHidden=T|Text=0.9mm|Name=Height
|RECORD=41|OwnerIndex=50|IndexInSheet=2|OwnerPartId=-1|Location.X=394|Location.Y=882|Color=8388608|FontID=1|IsHidden=T|Text=ON Semiconductor|Name=Manufacturer_Name
|RECORD=41|OwnerIndex=50|IndexInSheet=3|OwnerPartId=-1|Location.X=394|Location.Y=882|Color=8388608|FontID=1|IsHidden=T|Text=NC7WV125K8X|Name=Manufacturer_Part_Number
|RECORD=41|OwnerIndex=50|IndexInSheet=4|OwnerPartId=-1|Location.X=394|Location.Y=882|Color=8388608|FontID=1|IsHidden=T|Text=512-NC7WV125K8X|Name=Mouser Part Number
|RECORD=41|OwnerIndex=50|IndexInSheet=5|OwnerPartId=-1|Location.X=394|Location.Y=882|Color=8388608|FontID=3|IsHidden=T|Text=https://www.mouser.com/Search/Refine.aspx?Keyword=512-NC7WV125K8X|Name=Mouser Price/Stock
|RECORD=41|OwnerIndex=50|IndexInSheet=6|OwnerPartId=-1|Location.X=394|Location.Y=882|Color=8388608|FontID=1|IsHidden=T|Text=NC7WV125K8X|Name=Arrow Part Number
|RECORD=41|OwnerIndex=50|IndexInSheet=7|OwnerPartId=-1|Location.X=394|Location.Y=882|Color=8388608|FontID=3|IsHidden=T|Text=https://www.arrow.com/en/products/nc7wv125k8x/on-semiconductor|Name=Arrow Price/Stock
|RECORD=14|OwnerIndex=50|IsNotAccesible=T|IndexInSheet=8|OwnerPartId=1|Location.X=414|Location.Y=857|Corner.X=484|Corner.Y=982|LineWidth=1|Color=128|AreaColor=11599871|IsSolid=T
|RECORD=2|OwnerIndex=50|OwnerPartId=1|FormalType=1|Electrical=4|PinConglomerate=58|PinLength=20|Location.X=414|Location.Y=972|Designator=1|SwapIDPart=Ž&Ž||PinPropagationDelay=0.000000E+000
|RECORD=2|OwnerIndex=50|OwnerPartId=1|FormalType=1|Electrical=4|PinConglomerate=58|PinLength=20|Location.X=414|Location.Y=947|Designator=2|SwapIDPart=Ž&Ž||PinPropagationDelay=0.000000E+000
|RECORD=2|OwnerIndex=50|OwnerPartId=1|FormalType=1|Electrical=4|PinConglomerate=58|PinLength=20|Location.X=414|Location.Y=892|Designator=3|SwapIDPart=Ž&Ž||PinPropagationDelay=0.000000E+000
|RECORD=2|OwnerIndex=50|OwnerPartId=1|FormalType=1|Electrical=4|PinConglomerate=58|PinLength=20|Location.X=414|Location.Y=862|Name=GND|Designator=4|SwapIDPart=Ž&Ž||PinPropagationDelay=0.000000E+000
|RECORD=2|OwnerIndex=50|OwnerPartId=1|FormalType=1|Electrical=4|PinConglomerate=58|PinLength=20|Location.X=414|Location.Y=872|Name=VCC|Designator=8|SwapIDPart=Ž&Ž||PinPropagationDelay=0.000000E+000
|RECORD=2|OwnerIndex=50|OwnerPartId=1|FormalType=1|Electrical=4|PinConglomerate=58|PinLength=20|Location.X=414|Location.Y=917|Designator=7|SwapIDPart=Ž&Ž||PinPropagationDelay=0.000000E+000
|RECORD=2|OwnerIndex=50|OwnerPartId=1|FormalType=1|Electrical=4|PinConglomerate=56|PinLength=20|Location.X=484|Location.Y=947|Designator=6|SwapIDPart=Ž&Ž||PinPropagationDelay=0.000000E+000
|RECORD=2|OwnerIndex=50|OwnerPartId=1|FormalType=1|Electrical=4|PinConglomerate=56|PinLength=20|Location.X=484|Location.Y=892|Designator=5|SwapIDPart=Ž&Ž||PinPropagationDelay=0.000000E+000
|RECORD=6|OwnerIndex=50|IsNotAccesible=T|IndexInSheet=17|OwnerPartId=1|LineWidth=1|Color=16711680|LocationCount=4|X1=439|Y1=957|X2=439|Y2=937|X3=459|Y3=947|X4=439|Y4=957
|RECORD=12|OwnerIndex=50|IsNotAccesible=T|IndexInSheet=18|OwnerPartId=1|Location.X=449|Location.Y=954|Radius=1|Radius_Frac=79777|LineWidth=1|EndAngle=360.000|Color=16711680
|RECORD=6|OwnerIndex=50|IsNotAccesible=T|IndexInSheet=19|OwnerPartId=1|LineWidth=1|Color=16711680|LocationCount=4|X1=459|Y1=902|X2=459|Y2=882|X3=439|Y3=892|X4=459|Y4=902
|RECORD=12|OwnerIndex=50|IsNotAccesible=T|IndexInSheet=20|OwnerPartId=1|Location.X=449|Location.Y=899|Radius=1|Radius_Frac=79777|LineWidth=1|EndAngle=360.000|Color=16711680
|RECORD=6|OwnerIndex=50|IsNotAccesible=T|IndexInSheet=21|OwnerPartId=1|LineWidth=1|Color=16711680|LocationCount=3|X1=449|Y1=901|X2=449|Y2=917|X3=414|Y3=917
|RECORD=6|OwnerIndex=50|IsNotAccesible=T|IndexInSheet=22|OwnerPartId=1|LineWidth=1|Color=16711680|LocationCount=3|X1=449|Y1=956|X2=449|Y2=972|X3=414|Y3=972
|RECORD=6|OwnerIndex=50|IsNotAccesible=T|IndexInSheet=23|OwnerPartId=1|LineWidth=1|Color=16711680|LocationCount=2|X1=414|Y1=947|X2=439|Y2=947
|RECORD=6|OwnerIndex=50|IsNotAccesible=T|IndexInSheet=24|OwnerPartId=1|LineWidth=1|Color=16711680|LocationCount=2|X1=459|Y1=947|X2=484|Y2=947
|RECORD=6|OwnerIndex=50|IsNotAccesible=T|IndexInSheet=25|OwnerPartId=1|LineWidth=1|Color=16711680|LocationCount=2|X1=459|Y1=892|X2=484|Y2=892
|RECORD=6|OwnerIndex=50|IsNotAccesible=T|IndexInSheet=26|OwnerPartId=1|LineWidth=1|Color=16711680|LocationCount=2|X1=439|Y1=892|X2=414|Y2=892
|RECORD=34|OwnerIndex=50|IndexInSheet=-1|OwnerPartId=-1|Location.X=413|Location.Y=982|Color=8388608|FontID=1|Text=U8|Name=Designator|ReadOnlyState=1
|RECORD=41|OwnerIndex=50|IndexInSheet=-1|OwnerPartId=-1|Location.X=413|Location.Y=847|Color=8388608|FontID=1|Text=NC7WV125K8X|Name=Comment
|RECORD=44|OwnerIndex=50
|RECORD=45|OwnerIndex=88|IndexInSheet=-1|ModelName=SOP50P310X90-8N|ModelType=PCBLIB|DatafileCount=1|ModelDatafile0=C:\Users\<user>\Documents\AltiumLL\SamacSys.PcbLib|ModelDatafileEntity0=SOP50P310X90-8N|ModelDatafileKind0=PCBLIB|IsCurrent=T
|RECORD=46|OwnerIndex=89
|RECORD=48|OwnerIndex=89
|RECORD=17|IndexInSheet=35|OwnerPartId=-1|Style=4|ShowNetName=T|Location.X=704|Location.Y=817|Orientation=3|Color=128|FontID=1|Text=GND
|RECORD=1|LibReference=CN-1P-M-RF3|ComponentDescription=Ultra Miniature Coaxial Connector Jack, 60 V, 50 Ohm, -40 to 90 degC, RoHS, Tape and Reel|PartCount=2|DisplayModeCount=1|IndexInSheet=36|OwnerPartId=-1|Location.X=634|Location.Y=967|CurrentPartId=1|LibraryPath=*|SourceLibraryName=Altium Content Vault|TargetFileName=*|AreaColor=11599871|Color=128|PartIDLocked=T|DesignItemId=CMP-2000-07505-1|AllPinCount=3
|RECORD=8|OwnerIndex=93|IsNotAccesible=T|OwnerPartId=1|Location.X=654|Location.Y=947|Radius=20|SecondaryRadius=20|LineWidth=1|Color=16711680|AreaColor=16777215
|RECORD=8|OwnerIndex=93|IsNotAccesible=T|IndexInSheet=1|OwnerPartId=1|Location.X=654|Location.Y=947|Radius=4|SecondaryRadius=4|LineWidth=1|Color=16711680|AreaColor=16777215
|RECORD=2|OwnerIndex=93|OwnerPartId=1|FormalType=1|Electrical=4|PinConglomerate=51|PinLength=10|Location.X=644|Location.Y=927|Name=1|Designator=1|PinPropagationDelay=0.000000E+000
|RECORD=2|OwnerIndex=93|OwnerPartId=1|FormalType=1|Electrical=4|PinConglomerate=50|PinLength=10|Location.X=634|Location.Y=947|Name=2|Designator=2|PinPropagationDelay=0.000000E+000
|RECORD=2|OwnerIndex=93|OwnerPartId=1|FormalType=1|Electrical=4|PinConglomerate=51|PinLength=10|Location.X=664|Location.Y=927|Name=3|Designator=3|PinPropagationDelay=0.000000E+000
|RECORD=6|OwnerIndex=93|IsNotAccesible=T|IndexInSheet=5|OwnerPartId=1|LineWidth=1|Color=16711680|LocationCount=5|X1=634|Y1=927|X2=634|Y2=967|X3=674|Y3=967|X4=674|Y4=927|X5=634|Y5=927
|RECORD=6|OwnerIndex=93|IsNotAccesible=T|IndexInSheet=6|OwnerPartId=1|LineWidth=1|Color=16711680|LocationCount=2|X1=634|Y1=947|X2=650|Y2=947
|RECORD=41|OwnerIndex=93|IndexInSheet=7|OwnerPartId=-1|Location.X=622|Location.Y=968|Color=8388608|FontID=1|IsHidden=T|Text=Straight|Name=Orientation
|RECORD=41|OwnerIndex=93|IndexInSheet=8|OwnerPartId=-1|Location.X=622|Location.Y=968|Color=8388608|FontID=1|IsHidden=T|Text=Female|Name=Gender
|RECORD=41|OwnerIndex=93|IndexInSheet=9|OwnerPartId=-1|Location.X=622|Location.Y=968|Color=8388608|FontID=1|IsHidden=T|Text=Vertical|Name=PCB Mounting Orientation
|RECORD=41|OwnerIndex=93|IndexInSheet=10|OwnerPartId=-1|Location.X=622|Location.Y=968|Color=8388608|FontID=1|IsHidden=T|Text=SurfaceMount|Name=Mount
|RECORD=41|OwnerIndex=93|IndexInSheet=11|OwnerPartId=-1|Location.X=622|Location.Y=968|Color=8388608|FontID=1|IsHidden=T|Text=3mm|Name=Length
|RECORD=41|OwnerIndex=93|IndexInSheet=12|OwnerPartId=-1|Location.X=622|Location.Y=968|Color=8388608|FontID=1|IsHidden=T|Text=TapeandReel|Name=Packaging
|RECORD=41|OwnerIndex=93|IndexInSheet=13|OwnerPartId=-1|Location.X=622|Location.Y=968|Color=8388608|FontID=1|IsHidden=T|Text=Jack|Name=Connector Type
|RECORD=41|OwnerIndex=93|IndexInSheet=14|OwnerPartId=-1|Location.X=622|Location.Y=968|Color=8388608|FontID=1|IsHidden=T|Text=LeadFree|Name=Lead Free
|RECORD=41|OwnerIndex=93|IndexInSheet=15|OwnerPartId=-1|Location.X=622|Location.Y=968|Color=8388608|FontID=1|IsHidden=T|Text=1|Name=Package Quantity
|RECORD=41|OwnerIndex=93|IndexInSheet=16|OwnerPartId=-1|Location.X=622|Location.Y=968|Color=8388608|FontID=1|IsHidden=T|Text=SMD/SMT|Name=Termination
|RECORD=41|OwnerIndex=93|IndexInSheet=17|OwnerPartId=-1|Location.X=622|Location.Y=968|Color=8388608|FontID=1|IsHidden=T|Text=CopperAlloy|Name=Contact Material
|RECORD=41|OwnerIndex=93|IndexInSheet=18|OwnerPartId=-1|Location.X=622|Location.Y=968|Color=8388608|FontID=1|IsHidden=T|Text=Pull|Name=Fastening Type
|RECORD=41|OwnerIndex=93|IndexInSheet=19|OwnerPartId=-1|Location.X=622|Location.Y=968|Color=8388608|FontID=1|IsHidden=T|Text=true|Name=RoHSCompliant
|RECORD=41|OwnerIndex=93|IndexInSheet=20|OwnerPartId=-1|Location.X=622|Location.Y=968|Color=8388608|FontID=1|IsHidden=T|Text=LiquidCrystalPolymer|Name=Body Material
|RECORD=41|OwnerIndex=93|IndexInSheet=21|OwnerPartId=-1|Location.X=622|Location.Y=968|Color=8388608|FontID=1|IsHidden=T|Text=SMD/SMT|Name=Case\/Package
|RECORD=41|OwnerIndex=93|IndexInSheet=22|OwnerPartId=-1|Location.X=622|Location.Y=968|Color=8388608|FontID=1|IsHidden=T|Text=90degC|Name=Max Operating Temperature
|RECORD=41|OwnerIndex=93|IndexInSheet=23|OwnerPartId=-1|Location.X=622|Location.Y=968|Color=8388608|FontID=1|IsHidden=T|Text=50Ohm|Name=Impedance
|RECORD=41|OwnerIndex=93|IndexInSheet=24|OwnerPartId=-1|Location.X=622|Location.Y=968|Color=8388608|FontID=3|IsHidden=T|Text=http://www.te.com/commerce/DocumentDelivery/DDEController?Action=srchrtrv&DocNm=1909763&DocType=Customer+Drawing&DocLang=English|Name=Datasheet URL
|RECORD=41|OwnerIndex=93|IndexInSheet=25|OwnerPartId=-1|Location.X=622|Location.Y=968|Color=8388608|FontID=1|IsHidden=T|Text=Gold|Name=Contact Plating
|RECORD=41|OwnerIndex=93|IndexInSheet=26|OwnerPartId=-1|Location.X=622|Location.Y=968|Color=8388608|FontID=1|IsHidden=T|Text=SurfaceMount|Name=Mounting Technology
|RECORD=41|OwnerIndex=93|IndexInSheet=27|OwnerPartId=-1|Location.X=622|Location.Y=968|Color=8388608|FontID=1|IsHidden=T|Text=6GHz|Name=Max Frequency
|RECORD=41|OwnerIndex=93|IndexInSheet=28|OwnerPartId=-1|Location.X=622|Location.Y=968|Color=8388608|FontID=1|IsHidden=T|Text=TECO-1909763-1|Name=Package Reference
|RECORD=41|OwnerIndex=93|IndexInSheet=29|OwnerPartId=-1|Location.X=622|Location.Y=968|Color=8388608|FontID=1|IsHidden=T|Text=Thermoplastic|Name=Insulation Material
|RECORD=41|OwnerIndex=93|IndexInSheet=30|OwnerPartId=-1|Location.X=622|Location.Y=968|Color=8388608|FontID=1|IsHidden=T|Text=-40degC|Name=Min Operating Temperature
|RECORD=41|OwnerIndex=93|IndexInSheet=31|OwnerPartId=-1|Location.X=622|Location.Y=968|Color=8388608|FontID=3|IsHidden=T|Text=http://www.te.com/|Name=Manufacturer URL
|RECORD=41|OwnerIndex=93|IndexInSheet=32|OwnerPartId=-1|Location.X=622|Location.Y=968|Color=8388608|FontID=1|IsHidden=T|Text=Gold|Name=Body Plating
|RECORD=41|OwnerIndex=93|IndexInSheet=33|OwnerPartId=-1|Location.X=622|Location.Y=968|Color=8388608|FontID=1|IsHidden=T|Text=Polymer|Name=Dielectric Material
|RECORD=41|OwnerIndex=93|IndexInSheet=34|OwnerPartId=-1|Location.X=622|Location.Y=968|Color=8388608|FontID=1|IsHidden=T|Text=TE Connectivity|Name=Manufacturer
|RECORD=41|OwnerIndex=93|IndexInSheet=35|OwnerPartId=-1|Location.X=622|Location.Y=968|Color=8388608|FontID=1|IsHidden=T|Text=Compliant|Name=ELV
|RECORD=41|OwnerIndex=93|IndexInSheet=36|OwnerPartId=-1|Location.X=622|Location.Y=968|Color=8388608|FontID=1|IsHidden=T|Text=Rev. B2, 11/2015|Name=Datasheet Version
|RECORD=41|OwnerIndex=93|IndexInSheet=37|OwnerPartId=-1|Location.X=622|Location.Y=968|Color=8388608|FontID=1|IsHidden=T|Text=No|Name=Radiation Hardening
|RECORD=41|OwnerIndex=93|IndexInSheet=38|OwnerPartId=-1|Location.X=622|Location.Y=968|Color=8388608|FontID=1|IsHidden=T|Text=3-Pin Surface Mount Device, Body 2.6 x 2.6 mm|Name=Package Description
|RECORD=41|OwnerIndex=93|IndexInSheet=39|OwnerPartId=-1|Location.X=622|Location.Y=968|Color=8388608|FontID=1|IsHidden=T|Text=Beige|Name=Housing Colour
|RECORD=34|OwnerIndex=93|IndexInSheet=-1|OwnerPartId=-1|Location.X=633|Location.Y=968|Color=8388608|FontID=1|Text=J1|Name=Designator|ReadOnlyState=1
|RECORD=41|OwnerIndex=93|IndexInSheet=-1|OwnerPartId=-1|Location.X=684|Location.Y=927|Color=8388608|FontID=1|Text=1909763-1|Name=Comment
|RECORD=44|OwnerIndex=93
|RECORD=45|OwnerIndex=139|IndexInSheet=-1|Description=SMD, 3-Leads, Body 2.6x2.6mm, Height 1.25mm|UseComponentLibrary=T|ModelName=TECO-1909763-1_V|ModelType=PCBLIB|DatafileCount=1|ModelDatafileEntity0=TECO-1909763-1_V|ModelDatafileKind0=PCBLib|IsCurrent=T|DatalinksLocked=T|DatabaseDatalinksLocked=T
|RECORD=46|OwnerIndex=140
|RECORD=48|OwnerIndex=140
|RECORD=41|OwnerIndex=142|IndexInSheet=-1|OwnerPartId=-1|Color=8388608|FontID=1|Text=2D|Name=Available Preview Images
|RECORD=1|LibReference=CN-S-4F-RF5|ComponentDescription=Coaxial connector, 50 Ohm, -65 to 165 degC, 5-Pin THD, RoHS, Bulk|PartCount=2|DisplayModeCount=1|IndexInSheet=37|OwnerPartId=-1|Location.X=634|Location.Y=887|CurrentPartId=1|LibraryPath=*|SourceLibraryName=Altium Content Vault|TargetFileName=*|AreaColor=11599871|Color=128|PartIDLocked=T|DesignItemId=CMP-2000-05705-1|AllPinCount=5
|RECORD=2|OwnerIndex=144|OwnerPartId=1|FormalType=1|Electrical=4|PinConglomerate=51|PinLength=10|Location.X=674|Location.Y=847|Name=5|Designator=5|SwapIDPart=Ž&Ž1|PinPropagationDelay=0.000000E+000
|RECORD=8|OwnerIndex=144|IsNotAccesible=T|IndexInSheet=1|OwnerPartId=1|Location.X=654|Location.Y=867|Radius=20|SecondaryRadius=20|LineWidth=1|Color=16711680|AreaColor=16777215
|RECORD=8|OwnerIndex=144|IsNotAccesible=T|IndexInSheet=2|OwnerPartId=1|Location.X=654|Location.Y=867|Radius=4|SecondaryRadius=4|LineWidth=1|Color=16711680|AreaColor=16777215
|RECORD=2|OwnerIndex=144|OwnerPartId=1|FormalType=1|Electrical=4|PinConglomerate=50|PinLength=10|Location.X=634|Location.Y=867|Name=1|Designator=1|PinPropagationDelay=0.000000E+000
|RECORD=2|OwnerIndex=144|OwnerPartId=1|FormalType=1|Electrical=4|PinConglomerate=51|PinLength=10|Location.X=644|Location.Y=847|Name=2|Designator=2|PinPropagationDelay=0.000000E+000
|RECORD=2|OwnerIndex=144|OwnerPartId=1|FormalType=1|Electrical=4|PinConglomerate=51|PinLength=10|Location.X=654|Location.Y=847|Name=3|Designator=3|PinPropagationDelay=0.000000E+000
|RECORD=2|OwnerIndex=144|OwnerPartId=1|FormalType=1|Electrical=4|PinConglomerate=51|PinLength=10|Location.X=664|Location.Y=847|Name=4|Designator=4|PinPropagationDelay=0.000000E+000
|RECORD=6|OwnerIndex=144|IsNotAccesible=T|IndexInSheet=7|OwnerPartId=1|LineWidth=1|Color=16711680|LocationCount=5|X1=634|Y1=847|X2=634|Y2=887|X3=674|Y3=887|X4=674|Y4=847|X5=634|Y5=847
|RECORD=6|OwnerIndex=144|IsNotAccesible=T|IndexInSheet=8|OwnerPartId=1|LineWidth=1|Color=16711680|LocationCount=2|X1=634|Y1=867|X2=650|Y2=867
|RECORD=41|OwnerIndex=144|IndexInSheet=9|OwnerPartId=-1|Location.X=622|Location.Y=888|Color=8388608|FontID=1|IsHidden=T|Text=ThroughHole|Name=Mounting Technology
|RECORD=41|OwnerIndex=144|IndexInSheet=10|OwnerPartId=-1|Location.X=622|Location.Y=888|Color=8388608|FontID=1|IsHidden=T|Text=ThroughHole,RightAngle|Name=Mounting Type
|RECORD=41|OwnerIndex=144|IndexInSheet=11|OwnerPartId=-1|Location.X=622|Location.Y=888|Color=8388608|FontID=1|IsHidden=T|Text=-|Name=Cable Group
|RECORD=41|OwnerIndex=144|IndexInSheet=12|OwnerPartId=-1|Location.X=622|Location.Y=888|Color=8388608|FontID=1|IsHidden=T|Text=901-143-6RFXMountingHole|Name=Catalog Drawings
|RECORD=41|OwnerIndex=144|IndexInSheet=13|OwnerPartId=-1|Location.X=622|Location.Y=888|Color=8388608|FontID=1|IsHidden=T|Text=901-143-6RFX.igs|Name=3D Model
|RECORD=41|OwnerIndex=144|IndexInSheet=14|OwnerPartId=-1|Location.X=622|Location.Y=888|Color=8388608|FontID=1|IsHidden=T|Text=-|Name=Series
|RECORD=41|OwnerIndex=144|IndexInSheet=15|OwnerPartId=-1|Location.X=622|Location.Y=888|Color=8388608|FontID=1|IsHidden=T|Text=5-Pin Through Hole Device, Body 7 x 7 mm, Pitch 2.54 mm|Name=Package Description
|RECORD=41|OwnerIndex=144|IndexInSheet=16|OwnerPartId=-1|Location.X=622|Location.Y=888|Color=8388608|FontID=1|IsHidden=T|Text=901-143-6RFX|Name=Package Reference
|RECORD=41|OwnerIndex=144|IndexInSheet=17|OwnerPartId=-1|Location.X=622|Location.Y=888|Color=8388608|FontID=1|IsHidden=T|Text=Brass|Name=Body Material
|RECORD=41|OwnerIndex=144|IndexInSheet=18|OwnerPartId=-1|Location.X=622|Location.Y=888|Color=8388608|FontID=1|IsHidden=T|Text=-|Name=Voltage Rating
|RECORD=41|OwnerIndex=144|IndexInSheet=19|OwnerPartId=-1|Location.X=622|Location.Y=888|Color=8388608|FontID=1|IsHidden=T|Text=1|Name=Standard Package
|RECORD=41|OwnerIndex=144|IndexInSheet=20|OwnerPartId=-1|Location.X=622|Location.Y=888|Color=8388608|FontID=1|IsHidden=T|Text=Jack,FemaleSocket|Name=Connector Type
|RECORD=41|OwnerIndex=144|IndexInSheet=21|OwnerPartId=-1|Location.X=622|Location.Y=888|Color=8388608|FontID=1|IsHidden=T|Text=Threaded|Name=Fastening Type
|RECORD=41|OwnerIndex=144|IndexInSheet=22|OwnerPartId=-1|Location.X=622|Location.Y=888|Color=8388608|FontID=1|IsHidden=T|Text=Gold|Name=Housing Color
|RECORD=41|OwnerIndex=144|IndexInSheet=23|OwnerPartId=-1|Location.X=622|Location.Y=888|Color=8388608|FontID=1|IsHidden=T|Text=Solder|Name=Shield Termination
|RECORD=41|OwnerIndex=144|IndexInSheet=24|OwnerPartId=-1|Location.X=622|Location.Y=888|Color=8388608|FontID=1|IsHidden=T|Text=901-143-6-RFX9011436RFXARFX1232|Name=Other Names
|RECORD=41|OwnerIndex=144|IndexInSheet=25|OwnerPartId=-1|Location.X=622|Location.Y=888|Color=8388608|FontID=3|IsHidden=T|Text=http://www.amphenolrf.com/downloads/dl/file/id/2712/product/3102/901_143_6rfx_customer_drawing.pdf|Name=Datasheet URL
|RECORD=41|OwnerIndex=144|IndexInSheet=26|OwnerPartId=-1|Location.X=622|Location.Y=888|Color=8388608|FontID=1|IsHidden=T|Text=CoaxialConnectors(RF)|Name=Family
|RECORD=41|OwnerIndex=144|IndexInSheet=27|OwnerPartId=-1|Location.X=622|Location.Y=888|Color=8388608|FontID=1|IsHidden=T|Text=SMA,RFX|Name=Online Catalog
|RECORD=41|OwnerIndex=144|IndexInSheet=28|OwnerPartId=-1|Location.X=622|Location.Y=888|Color=8388608|FontID=1|IsHidden=T|Text=18GHz|Name=Frequency - Max
|RECORD=41|OwnerIndex=144|IndexInSheet=29|OwnerPartId=-1|Location.X=622|Location.Y=888|Color=8388608|FontID=1|IsHidden=T|Text=Solder|Name=Contact Termination
|RECORD=41|OwnerIndex=144|IndexInSheet=30|OwnerPartId=-1|Location.X=622|Location.Y=888|Color=8388608|FontID=3|IsHidden=T|Text=http://www.amphenol.com/|Name=Manufacturer URL
|RECORD=41|OwnerIndex=144|IndexInSheet=31|OwnerPartId=-1|Location.X=622|Location.Y=888|Color=8388608|FontID=1|IsHidden=T|Text=Amphenol|Name=Manufacturer
|RECORD=41|OwnerIndex=144|IndexInSheet=32|OwnerPartId=-1|Location.X=622|Location.Y=888|Color=8388608|FontID=1|IsHidden=T|Text=-65°C~165°C|Name=Operating Temperature
|RECORD=41|OwnerIndex=144|IndexInSheet=33|OwnerPartId=-1|Location.X=622|Location.Y=888|Color=8388608|FontID=1|IsHidden=T|Text=Connectors,Interconnects|Name=Category
|RECORD=41|OwnerIndex=144|IndexInSheet=34|OwnerPartId=-1|Location.X=622|Location.Y=888|Color=8388608|FontID=1|IsHidden=T|Text=Bulk|Name=Packaging
|RECORD=41|OwnerIndex=144|IndexInSheet=35|OwnerPartId=-1|Location.X=622|Location.Y=888|Color=8388608|FontID=1|IsHidden=T|Text=Gold|Name=Body Finish
|RECORD=41|OwnerIndex=144|IndexInSheet=36|OwnerPartId=-1|Location.X=622|Location.Y=888|Color=8388608|FontID=1|IsHidden=T|Text=Polytetrafluoroethylene(PTFE)|Name=Dielectric Material
|RECORD=41|OwnerIndex=144|IndexInSheet=37|OwnerPartId=-1|Location.X=622|Location.Y=888|Color=8388608|FontID=1|IsHidden=T|Text=BerylliumCopper|Name=Center Contact Material
|RECORD=41|OwnerIndex=144|IndexInSheet=38|OwnerPartId=-1|Location.X=622|Location.Y=888|Color=8388608|FontID=1|IsHidden=T|Text=50Ohm|Name=Impedance
|RECORD=41|OwnerIndex=144|IndexInSheet=39|OwnerPartId=-1|Location.X=622|Location.Y=888|Color=8388608|FontID=1|IsHidden=T|Text=-|Name=Features
|RECORD=41|OwnerIndex=144|IndexInSheet=40|OwnerPartId=-1|Location.X=622|Location.Y=888|Color=8388608|FontID=1|IsHidden=T|Text=SMA|Name=Connector Style
|RECORD=41|OwnerIndex=144|IndexInSheet=41|OwnerPartId=-1|Location.X=622|Location.Y=888|Color=8388608|FontID=1|IsHidden=T|Text=Gold|Name=Center Contact Plating
|RECORD=41|OwnerIndex=144|IndexInSheet=42|OwnerPartId=-1|Location.X=622|Location.Y=888|Color=8388608|FontID=1|IsHidden=T|Text=Rev. C, 06/2010|Name=Datasheet Version
|RECORD=41|OwnerIndex=144|IndexInSheet=43|OwnerPartId=-1|Location.X=622|Location.Y=888|Color=8388608|FontID=1|IsHidden=T|Text=-|Name=Ingress Protection
|RECORD=34|OwnerIndex=144|IndexInSheet=-1|OwnerPartId=-1|Location.X=633|Location.Y=888|Color=8388608|FontID=1|Text=AN1|Name=Designator|ReadOnlyState=1
|RECORD=41|OwnerIndex=144|IndexInSheet=-1|OwnerPartId=-1|Location.X=684|Location.Y=837|Color=8388608|FontID=1|Text=RF2-49B-T-00-50-G-HDW|Name=Comment
|RECORD=44|OwnerIndex=144
|RECORD=45|OwnerIndex=196|IndexInSheet=-1|Description=THD, 5-Leads, Body 7x7mm, Pitch 2.54mm|UseComponentLibrary=T|ModelName=AMPH-901-143-6RFX_V|ModelType=PCBLIB|DatafileCount=1|ModelDatafileEntity0=AMPH-901-143-6RFX_V|ModelDatafileKind0=PCBLib|IsCurrent=T|DatalinksLocked=T|DatabaseDatalinksLocked=T
|RECORD=46|OwnerIndex=197
|RECORD=48|OwnerIndex=197
|RECORD=41|OwnerIndex=199|IndexInSheet=-1|OwnerPartId=-1|Color=8388608|FontID=1|Text=2D|Name=Available Preview Images
|RECORD=17|IndexInSheet=38|OwnerPartId=-1|Style=4|ShowNetName=T|Location.X=704|Location.Y=907|Orientation=3|Color=128|FontID=1|Text=GND
|RECORD=1|LibReference=RES-2|ComponentDescription=General Purpose Chip Resistor, 49.9 Ohm, +/- 1%, -55 to 155 degC, 0603 (1608 Metric), RoHS, Tape and Reel|PartCount=2|DisplayModeCount=1|IndexInSheet=39|OwnerPartId=-1|Location.X=539|Location.Y=947|CurrentPartId=1|LibraryPath=*|SourceLibraryName=Altium Content Vault|TargetFileName=*|AreaColor=11599871|Color=128|PartIDLocked=T|DesignItemId=CMP-1659-00036-1|AllPinCount=2
|RECORD=2|OwnerIndex=202|OwnerPartId=1|FormalType=1|Electrical=4|PinConglomerate=32|PinLength=10|Location.X=559|Location.Y=947|Name=2|Designator=2|PinPropagationDelay=0.000000E+000
|RECORD=2|OwnerIndex=202|OwnerPartId=1|FormalType=1|Electrical=4|PinConglomerate=34|PinLength=10|Location.X=539|Location.Y=947|Name=1|Designator=1|PinPropagationDelay=0.000000E+000
|RECORD=6|OwnerIndex=202|IsNotAccesible=T|IndexInSheet=2|OwnerPartId=1|LineWidth=1|Color=16711680|LocationCount=10|X1=559|Y1=947|X2=555|Y2=947|X3=554|Y3=945|X4=552|Y4=949|X5=550|Y5=945|X6=548|Y6=949|X7=546|Y7=945|X8=544|Y8=949|X9=543|Y9=947|X10=539|Y10=947
|RECORD=41|OwnerIndex=202|IndexInSheet=3|OwnerPartId=-1|Location.X=527|Location.Y=962|Color=8388608|FontID=1|IsHidden=T|Text=0603|Name=PackageReference
|RECORD=41|OwnerIndex=202|IndexInSheet=4|OwnerPartId=-1|Location.X=527|Location.Y=962|Color=8388608|FontID=1|IsHidden=T|Text=Tray|Name=Packaging
|RECORD=41|OwnerIndex=202|IndexInSheet=5|OwnerPartId=-1|Location.X=527|Location.Y=962|Color=8388608|FontID=1|IsHidden=T|Text=Datasheet|Name=ComponentLink2Description
|RECORD=41|OwnerIndex=202|IndexInSheet=6|OwnerPartId=-1|Location.X=527|Location.Y=962|Color=8388608|FontID=1|IsHidden=T|Text=Manufacturer URL|Name=ComponentLink1Description
|RECORD=41|OwnerIndex=202|IndexInSheet=7|OwnerPartId=-1|Location.X=527|Location.Y=962|Color=8388608|FontID=3|IsHidden=T|Text=https://datasheet.ciiva.com/11808/0900766b80f96399-11808223.pdf|Name=ComponentLink2URL
|RECORD=41|OwnerIndex=202|IndexInSheet=8|OwnerPartId=-1|Location.X=527|Location.Y=962|Color=8388608|FontID=1|IsHidden=T|Text=true|Name=RoHSCompliant
|RECORD=41|OwnerIndex=202|IndexInSheet=9|OwnerPartId=-1|Location.X=527|Location.Y=962|Color=8388608|FontID=1|IsHidden=T|Text=85 degC|Name=Max Operating Temperature
|RECORD=41|OwnerIndex=202|IndexInSheet=10|OwnerPartId=-1|Location.X=527|Location.Y=962|Color=8388608|FontID=1|IsHidden=T|Text=3.63 V|Name=Max Supply Voltage
|RECORD=41|OwnerIndex=202|IndexInSheet=11|OwnerPartId=-1|Location.X=527|Location.Y=962|Color=8388608|FontID=3|IsHidden=T|Text=http://www.yageo.com/|Name=ComponentLink1URL
|RECORD=41|OwnerIndex=202|IndexInSheet=12|OwnerPartId=-1|Location.X=527|Location.Y=962|Color=8388608|FontID=1|IsHidden=T|Text=2-Pin Surface Mount Device, Body 1.6 x 0.8 mm|Name=PackageDescription
|RECORD=41|OwnerIndex=202|IndexInSheet=13|OwnerPartId=-1|Location.X=527|Location.Y=962|Color=8388608|FontID=1|IsHidden=T|Text=LQFP|Name=Case\Package
|RECORD=41|OwnerIndex=202|IndexInSheet=14|OwnerPartId=-1|Location.X=527|Location.Y=962|Color=8388608|FontID=1|IsHidden=T|Text=Rev. 4, 04/2009|Name=DatasheetVersion
|RECORD=41|OwnerIndex=202|IndexInSheet=15|OwnerPartId=-1|Location.X=527|Location.Y=962|Color=8388608|FontID=1|IsHidden=T|Text=-40 degC|Name=Min Operating Temperature
|RECORD=41|OwnerIndex=202|IndexInSheet=16|OwnerPartId=-1|Location.X=527|Location.Y=962|Color=8388608|FontID=1|IsHidden=T|Text=SPI|Name=Interface
|RECORD=41|OwnerIndex=202|IndexInSheet=17|OwnerPartId=-1|Location.X=527|Location.Y=962|Color=8388608|FontID=1|IsHidden=T|Text=250|Name=Package Quantity
|RECORD=41|OwnerIndex=202|IndexInSheet=18|OwnerPartId=-1|Location.X=527|Location.Y=962|Color=8388608|FontID=1|IsHidden=T|Text=2.97 V|Name=Min Supply Voltage
|RECORD=41|OwnerIndex=202|IndexInSheet=19|OwnerPartId=-1|Location.X=527|Location.Y=962|Color=8388608|FontID=1|IsHidden=T|Text=48|Name=Pins
|RECORD=34|OwnerIndex=202|IndexInSheet=-1|OwnerPartId=-1|Location.X=538|Location.Y=950|Color=8388608|FontID=1|Text=R25|Name=Designator|ReadOnlyState=1
|RECORD=41|OwnerIndex=202|IndexInSheet=-1|OwnerPartId=-1|Location.X=538|Location.Y=934|Color=8388608|FontID=1|Text=49.9R|Name=Comment
|RECORD=44|OwnerIndex=202
|RECORD=45|OwnerIndex=227|IndexInSheet=-1|Description=Chip Resistor, 2-Leads, Body 1.70x0.90mm, IPC Medium Density|UseComponentLibrary=T|ModelName=RESC1608X55X25NL10T15|ModelType=PCBLIB|DatafileCount=1|ModelDatafileEntity0=RESC1608X55X25NL10T15|ModelDatafileKind0=PCBLib|IsCurrent=T|DatalinksLocked=T|DatabaseDatalinksLocked=T
|RECORD=46|OwnerIndex=228
|RECORD=48|OwnerIndex=228
|RECORD=41|OwnerIndex=230|IndexInSheet=-1|OwnerPartId=-1|Color=8388608|FontID=1|IsHidden=T|Text=2D|Name=Available Preview Images
|RECORD=45|OwnerIndex=227|IndexInSheet=-1|Description=Chip Resistor, 2-Leads, Body 1.70x0.90mm, IPC Low Density|UseComponentLibrary=T|ModelName=RESC1608X55X25ML10T15|ModelType=PCBLIB|DatafileCount=1|ModelDatafileEntity0=RESC1608X55X25ML10T15|ModelDatafileKind0=PCBLib|DatalinksLocked=T|DatabaseDatalinksLocked=T
|RECORD=46|OwnerIndex=232
|RECORD=48|OwnerIndex=232
|RECORD=41|OwnerIndex=234|IndexInSheet=-1|OwnerPartId=-1|Color=8388608|FontID=1|IsHidden=T|Text=2D|Name=Available Preview Images
|RECORD=45|OwnerIndex=227|IndexInSheet=-1|Description=Chip Resistor, 2-Leads, Body 1.70x0.90mm, IPC High Density|UseComponentLibrary=T|ModelName=RESC1608X55X25LL10T15|ModelType=PCBLIB|DatafileCount=1|ModelDatafileEntity0=RESC1608X55X25LL10T15|ModelDatafileKind0=PCBLib|DatalinksLocked=T|DatabaseDatalinksLocked=T
|RECORD=46|OwnerIndex=236
|RECORD=48|OwnerIndex=236
|RECORD=41|OwnerIndex=238|IndexInSheet=-1|OwnerPartId=-1|Color=8388608|FontID=1|IsHidden=T|Text=2D|Name=Available Preview Images
|RECORD=17|IndexInSheet=40|OwnerPartId=-1|ShowNetName=T|Location.X=264|Location.Y=947|Orientation=2|Color=255|FontID=1|Text=ANT1_OUT|IsCrossSheetConnector=T
|RECORD=17|IndexInSheet=41|OwnerPartId=-1|ShowNetName=T|Location.X=270|Location.Y=1050|Orientation=1|Color=128|FontID=1|Text=+3.3V
|RECORD=17|IndexInSheet=42|OwnerPartId=-1|ShowNetName=T|Location.X=300|Location.Y=1060|Orientation=1|Color=128|FontID=1|Text=+3.3V
|RECORD=17|IndexInSheet=43|OwnerPartId=-1|ShowNetName=T|Location.X=264|Location.Y=892|Orientation=2|Color=255|FontID=1|Text=ANT1_IN|IsCrossSheetConnector=T
|RECORD=17|IndexInSheet=44|OwnerPartId=-1|Style=4|ShowNetName=T|Location.X=384|Location.Y=817|Orientation=3|Color=128|FontID=1|Text=GND
|RECORD=17|IndexInSheet=45|OwnerPartId=-1|Style=4|ShowNetName=T|Location.X=334|Location.Y=817|Orientation=3|Color=128|FontID=1|Text=GND
|RECORD=17|IndexInSheet=46|OwnerPartId=-1|ShowNetName=T|Location.X=334|Location.Y=1037|Orientation=1|Color=128|FontID=1|Text=+3.3V
|RECORD=1|LibReference=WE-TVS-HS-4|ComponentDescription=TVS Diode WE-TVS-HS, VRWM=3.3V|PartCount=2|DisplayModeCount=1|IndexInSheet=47|OwnerPartId=-1|Location.X=574|Location.Y=757|Orientation=1|CurrentPartId=1|LibraryPath=*|SourceLibraryName=Altium Content Vault|TargetFileName=*|AreaColor=11599871|Color=128|PartIDLocked=F|DesignItemId=CMP-1486-00002-1|AllPinCount=4
|RECORD=14|OwnerIndex=247|IsNotAccesible=T|OwnerPartId=1|Location.X=568|Location.Y=734|Corner.X=608|Corner.Y=772|AreaColor=11599871|IsSolid=T|Transparent=T
|RECORD=6|OwnerIndex=247|IsNotAccesible=T|IndexInSheet=1|OwnerPartId=1|LineWidth=1|Color=16711680|LocationCount=4|X1=578|X1_Frac=10000|Y1=758|Y1_Frac=40000|X2=576|X2_Frac=10000|Y2=756|Y2_Frac=40000|X3=572|X3_Frac=10000|Y3=756|Y3_Frac=40000|X4=570|X4_Frac=10000|Y4=754|Y4_Frac=40000
|RECORD=7|OwnerIndex=247|IsNotAccesible=T|IndexInSheet=2|OwnerPartId=1|LineWidth=1|Color=16711680|AreaColor=16711680|IsSolid=T|LocationCount=3|X1=578|X1_Frac=90000|Y1=750|Y1_Frac=50000|X2=573|X2_Frac=90000|Y2=755|Y2_Frac=50000|X3=568|X3_Frac=90000|Y3=750|Y3_Frac=50000
|RECORD=12|OwnerIndex=247|IsNotAccesible=T|IndexInSheet=3|OwnerPartId=1|Location.X=585|Location.Y=755|Radius_Frac=63392|LineWidth=1|StartAngle=57.394|EndAngle=30.947
|RECORD=6|OwnerIndex=247|IsNotAccesible=T|IndexInSheet=4|OwnerPartId=1|LineWidth=1|LocationCount=2|X1=594|Y1=755|X2=585|Y2=755
|RECORD=7|OwnerIndex=247|IsNotAccesible=T|IndexInSheet=5|OwnerPartId=1|LineWidth=1|Color=16711680|AreaColor=16711680|LocationCount=3|X1=589|X1_Frac=90000|Y1=742|Y1_Frac=50000|X2=584|X2_Frac=90000|Y2=747|Y2_Frac=50000|X3=579|X3_Frac=90000|Y3=742|Y3_Frac=50000
|RECORD=6|OwnerIndex=247|IsNotAccesible=T|IndexInSheet=6|OwnerPartId=1|LineWidth=1|Color=16711680|LocationCount=2|X1=581|Y1=748|X2=588|X2_Frac=87402|Y2=748
|RECORD=7|OwnerIndex=247|IsNotAccesible=T|IndexInSheet=7|OwnerPartId=1|LineWidth=1|Color=16711680|AreaColor=16711680|LocationCount=3|X1=589|X1_Frac=90000|Y1=758|Y1_Frac=50000|X2=584|X2_Frac=90000|Y2=763|Y2_Frac=50000|X3=579|X3_Frac=90000|Y3=758|Y3_Frac=50000
|RECORD=6|OwnerIndex=247|IsNotAccesible=T|IndexInSheet=8|OwnerPartId=1|LineWidth=1|Color=16711680|LocationCount=2|X1=581|Y1=764|X2=588|X2_Frac=87402|Y2=764
|RECORD=6|OwnerIndex=247|IsNotAccesible=T|IndexInSheet=9|OwnerPartId=1|LineWidth=1|LocationCount=2|X1=585|Y1=748|X2=585|Y2=758
|RECORD=6|OwnerIndex=247|IsNotAccesible=T|IndexInSheet=10|OwnerPartId=1|LineWidth=1|LocationCount=2|X1=585|Y1=764|X2=585|Y2=770
|RECORD=6|OwnerIndex=247|IsNotAccesible=T|IndexInSheet=11|OwnerPartId=1|LineWidth=1|LocationCount=2|X1=574|Y1=757|X2=574|Y2=770
|RECORD=6|OwnerIndex=247|IsNotAccesible=T|IndexInSheet=12|OwnerPartId=1|LineWidth=1|LocationCount=2|X1=574|Y1=736|X2=574|Y2=750
|RECORD=6|OwnerIndex=247|IsNotAccesible=T|IndexInSheet=13|OwnerPartId=1|LineWidth=1|LocationCount=2|X1=585|Y1=736|X2=585|Y2=742
|RECORD=6|OwnerIndex=247|IsNotAccesible=T|IndexInSheet=14|OwnerPartId=1|LineWidth=1|LocationCount=2|X1=574|Y1=736|X2=602|Y2=736
|RECORD=6|OwnerIndex=247|IsNotAccesible=T|IndexInSheet=15|OwnerPartId=1|LineWidth=1|LocationCount=2|X1=574|Y1=770|X2=602|Y2=770
|RECORD=6|OwnerIndex=247|IsNotAccesible=T|IndexInSheet=16|OwnerPartId=1|LineWidth=1|LocationCount=2|X1=594|Y1=751|X2=594|Y2=737
|RECORD=2|OwnerIndex=247|OwnerPartId=1|FormalType=1|Electrical=4|PinConglomerate=51|PinLength=10|Location.X=574|Location.Y=737|Name=GND|Designator=1|PinPropagationDelay=0.000000E+000
|RECORD=2|OwnerIndex=247|OwnerPartId=1|FormalType=1|Electrical=4|PinConglomerate=51|PinLength=10|Location.X=594|Location.Y=737|Name=I/O1|Designator=2|PinPropagationDelay=0.000000E+000
|RECORD=2|OwnerIndex=247|OwnerPartId=1|FormalType=1|Electrical=4|PinConglomerate=49|PinLength=10|Location.X=594|Location.Y=767|Name=I/O2|Designator=3|PinPropagationDelay=0.000000E+000
|RECORD=2|OwnerIndex=247|OwnerPartId=1|FormalType=1|Electrical=4|PinConglomerate=49|PinLength=10|Location.X=574|Location.Y=767|Name=VDD|Designator=4|PinPropagationDelay=0.000000E+000
|RECORD=12|OwnerIndex=247|IsNotAccesible=T|IndexInSheet=21|OwnerPartId=1|Location.X=574|Location.Y=770|Radius_Frac=63392|LineWidth=1|StartAngle=57.394|EndAngle=30.947
|RECORD=12|OwnerIndex=247|IsNotAccesible=T|IndexInSheet=22|OwnerPartId=1|Location.X=574|Location.Y=736|Radius_Frac=63392|LineWidth=1|StartAngle=57.394|EndAngle=30.947
|RECORD=12|OwnerIndex=247|IsNotAccesible=T|IndexInSheet=23|OwnerPartId=1|Location.X=602|Location.Y=751|Radius_Frac=63392|LineWidth=1|StartAngle=57.394|EndAngle=30.947
|RECORD=6|OwnerIndex=247|IsNotAccesible=T|IndexInSheet=24|OwnerPartId=1|LineWidth=1|LocationCount=2|X1=594|Y1=751|X2=602|Y2=751
|RECORD=7|OwnerIndex=247|IsNotAccesible=T|IndexInSheet=25|OwnerPartId=1|LineWidth=1|Color=16711680|AreaColor=16711680|LocationCount=3|X1=606|X1_Frac=90000|Y1=742|Y1_Frac=50000|X2=601|X2_Frac=90000|Y2=747|Y2_Frac=50000|X3=596|X3_Frac=90000|Y3=742|Y3_Frac=50000
|RECORD=6|OwnerIndex=247|IsNotAccesible=T|IndexInSheet=26|OwnerPartId=1|LineWidth=1|Color=16711680|LocationCount=2|X1=598|Y1=748|X2=605|X2_Frac=87402|Y2=748
|RECORD=7|OwnerIndex=247|IsNotAccesible=T|IndexInSheet=27|OwnerPartId=1|LineWidth=1|Color=16711680|AreaColor=16711680|LocationCount=3|X1=606|X1_Frac=90000|Y1=758|Y1_Frac=50000|X2=601|X2_Frac=90000|Y2=763|Y2_Frac=50000|X3=596|X3_Frac=90000|Y3=758|Y3_Frac=50000
|RECORD=6|OwnerIndex=247|IsNotAccesible=T|IndexInSheet=28|OwnerPartId=1|LineWidth=1|Color=16711680|LocationCount=2|X1=598|Y1=764|X2=605|X2_Frac=87402|Y2=764
|RECORD=6|OwnerIndex=247|IsNotAccesible=T|IndexInSheet=29|OwnerPartId=1|LineWidth=1|LocationCount=2|X1=602|Y1=748|X2=602|Y2=758
|RECORD=6|OwnerIndex=247|IsNotAccesible=T|IndexInSheet=30|OwnerPartId=1|LineWidth=1|LocationCount=2|X1=602|Y1=764|X2=602|Y2=770
|RECORD=6|OwnerIndex=247|IsNotAccesible=T|IndexInSheet=31|OwnerPartId=1|LineWidth=1|LocationCount=2|X1=602|Y1=736|X2=602|Y2=742
|RECORD=12|OwnerIndex=247|IsNotAccesible=T|IndexInSheet=32|OwnerPartId=1|Location.X=585|Location.Y=770|Radius_Frac=63392|LineWidth=1|StartAngle=57.394|EndAngle=30.947
|RECORD=12|OwnerIndex=247|IsNotAccesible=T|IndexInSheet=33|OwnerPartId=1|Location.X=585|Location.Y=736|Radius_Frac=63392|LineWidth=1|StartAngle=57.394|EndAngle=30.947
|RECORD=6|OwnerIndex=247|IsNotAccesible=T|IndexInSheet=34|OwnerPartId=1|LineWidth=1|LocationCount=2|X1=594|Y1=755|X2=594|Y2=772
|RECORD=41|OwnerIndex=247|IndexInSheet=35|OwnerPartId=-1|Location.X=567|Location.X_Frac=90000|Location.Y=779|Color=8388608|FontID=1|IsHidden=T|Text=8240136|Name=PartNumber
|RECORD=41|OwnerIndex=247|IndexInSheet=36|OwnerPartId=-1|Location.X=567|Location.X_Frac=90000|Location.Y=779|Color=8388608|FontID=1|IsHidden=T|Text=Manufacturer URL|Name=ComponentLink1Description
|RECORD=41|OwnerIndex=247|IndexInSheet=37|OwnerPartId=-1|Location.X=567|Location.X_Frac=90000|Location.Y=779|Color=8388608|FontID=1|IsHidden=T|Text=Wuerth Elektronik|Name=Manufacturer
|RECORD=41|OwnerIndex=247|IndexInSheet=38|OwnerPartId=-1|Location.X=567|Location.X_Frac=90000|Location.Y=779|Color=8388608|FontID=1|IsHidden=T|Text=SOT143-4L|Name=PackageReference
|RECORD=41|OwnerIndex=247|IndexInSheet=39|OwnerPartId=-1|Location.X=567|Location.X_Frac=90000|Location.Y=779|Color=8388608|FontID=3|IsHidden=T|Text=http://www.we-online.com|Name=ComponentLink1URL
|RECORD=41|OwnerIndex=247|IndexInSheet=40|OwnerPartId=-1|Location.X=567|Location.X_Frac=90000|Location.Y=779|Color=8388608|FontID=1|IsHidden=T|Text=3.3V|Name=Reverse Stand Off Voltage
|RECORD=41|OwnerIndex=247|IndexInSheet=41|OwnerPartId=-1|Location.X=567|Location.X_Frac=90000|Location.Y=779|Color=8388608|FontID=1|IsHidden=T|Text=Datasheet|Name=ComponentLink2Description
|RECORD=41|OwnerIndex=247|IndexInSheet=42|OwnerPartId=-1|Location.X=567|Location.X_Frac=90000|Location.Y=779|Color=8388608|FontID=3|IsHidden=T|Text=http://katalog.we-online.de/kataloge/eisos/media/pdf/8240136.pdf|Name=ComponentLink2URL
|RECORD=34|OwnerIndex=247|IndexInSheet=-1|OwnerPartId=-1|Location.X=608|Location.Y=763|Color=8388608|FontID=1|Text=D1|Name=Designator|ReadOnlyState=1
|RECORD=41|OwnerIndex=247|IndexInSheet=-1|OwnerPartId=-1|Location.X=608|Location.Y=753|Color=8388608|FontID=1|Text=8240136|Name=Comment
|RECORD=44|OwnerIndex=247
|RECORD=45|OwnerIndex=297|IndexInSheet=-1|Description=SOT143-4L, 4-Leads, Body 2.95x2.4mm, Pitch 1.70/1.90mm|UseComponentLibrary=T|ModelName=SOT143-4L|ModelType=PCBLIB|DatafileCount=1|ModelDatafileEntity0=SOT143-4L|ModelDatafileKind0=PCBLib|IsCurrent=T|DatalinksLocked=T|DatabaseDatalinksLocked=T
|RECORD=46|OwnerIndex=298
|RECORD=48|OwnerIndex=298
|RECORD=41|OwnerIndex=300|IndexInSheet=-1|OwnerPartId=-1|Color=8388608|FontID=1|IsHidden=T|Text=2D|Name=Available Preview Images
|RECORD=1|LibReference=NC7WV125K8X|ComponentDescription=Integrated Circuit|PartCount=2|DisplayModeCount=1|IndexInSheet=48|OwnerPartId=-1|Location.X=1154|Location.Y=882|CurrentPartId=1|LibraryPath=*|SourceLibraryName=SamacSys.SchLib|TargetFileName=*|AreaColor=11599871|Color=128|PartIDLocked=T|DesignItemId=NC7WV125K8X|AllPinCount=8
|RECORD=41|OwnerIndex=302|OwnerPartId=-1|Location.X=1154|Location.Y=882|Color=8388608|FontID=3|IsHidden=T|Text=https://www.mouser.com/datasheet/2/308/NC7WV125-1301459.pdf|Name=Datasheet Link
|RECORD=41|OwnerIndex=302|IndexInSheet=1|OwnerPartId=-1|Location.X=1154|Location.Y=882|Color=8388608|FontID=1|IsHidden=T|Text=0.9mm|Name=Height
|RECORD=41|OwnerIndex=302|IndexInSheet=2|OwnerPartId=-1|Location.X=1154|Location.Y=882|Color=8388608|FontID=1|IsHidden=T|Text=ON Semiconductor|Name=Manufacturer_Name
|RECORD=41|OwnerIndex=302|IndexInSheet=3|OwnerPartId=-1|Location.X=1154|Location.Y=882|Color=8388608|FontID=1|IsHidden=T|Text=NC7WV125K8X|Name=Manufacturer_Part_Number
|RECORD=41|OwnerIndex=302|IndexInSheet=4|OwnerPartId=-1|Location.X=1154|Location.Y=882|Color=8388608|FontID=1|IsHidden=T|Text=512-NC7WV125K8X|Name=Mouser Part Number
|RECORD=41|OwnerIndex=302|IndexInSheet=5|OwnerPartId=-1|Location.X=1154|Location.Y=882|Color=8388608|FontID=3|IsHidden=T|Text=https://www.mouser.com/Search/Refine.aspx?Keyword=512-NC7WV125K8X|Name=Mouser Price/Stock
|RECORD=41|OwnerIndex=302|IndexInSheet=6|OwnerPartId=-1|Location.X=1154|Location.Y=882|Color=8388608|FontID=1|IsHidden=T|Text=NC7WV125K8X|Name=Arrow Part Number
|RECORD=41|OwnerIndex=302|IndexInSheet=7|OwnerPartId=-1|Location.X=1154|Location.Y=882|Color=8388608|FontID=3|IsHidden=T|Text=https://www.arrow.com/en/products/nc7wv125k8x/on-semiconductor|Name=Arrow Price/Stock
|RECORD=14|OwnerIndex=302|IsNotAccesible=T|IndexInSheet=8|OwnerPartId=1|Location.X=1174|Location.Y=857|Corner.X=1244|Corner.Y=982|LineWidth=1|Color=128|AreaColor=11599871|IsSolid=T
|RECORD=2|OwnerIndex=302|OwnerPartId=1|FormalType=1|Electrical=4|PinConglomerate=58|PinLength=20|Location.X=1174|Location.Y=972|Designator=1|SwapIDPart=Ž&Ž||PinPropagationDelay=0.000000E+000
|RECORD=2|OwnerIndex=302|OwnerPartId=1|FormalType=1|Electrical=4|PinConglomerate=58|PinLength=20|Location.X=1174|Location.Y=947|Designator=2|SwapIDPart=Ž&Ž||PinPropagationDelay=0.000000E+000
|RECORD=2|OwnerIndex=302|OwnerPartId=1|FormalType=1|Electrical=4|PinConglomerate=58|PinLength=20|Location.X=1174|Location.Y=892|Designator=3|SwapIDPart=Ž&Ž||PinPropagationDelay=0.000000E+000
|RECORD=2|OwnerIndex=302|OwnerPartId=1|FormalType=1|Electrical=4|PinConglomerate=58|PinLength=20|Location.X=1174|Location.Y=862|Name=GND|Designator=4|SwapIDPart=Ž&Ž||PinPropagationDelay=0.000000E+000
|RECORD=2|OwnerIndex=302|OwnerPartId=1|FormalType=1|Electrical=4|PinConglomerate=58|PinLength=20|Location.X=1174|Location.Y=872|Name=VCC|Designator=8|SwapIDPart=Ž&Ž||PinPropagationDelay=0.000000E+000
|RECORD=2|OwnerIndex=302|OwnerPartId=1|FormalType=1|Electrical=4|PinConglomerate=58|PinLength=20|Location.X=1174|Location.Y=917|Designator=7|SwapIDPart=Ž&Ž||PinPropagationDelay=0.000000E+000
|RECORD=2|OwnerIndex=302|OwnerPartId=1|FormalType=1|Electrical=4|PinConglomerate=56|PinLength=20|Location.X=1244|Location.Y=947|Designator=6|SwapIDPart=Ž&Ž||PinPropagationDelay=0.000000E+000
|RECORD=2|OwnerIndex=302|OwnerPartId=1|FormalType=1|Electrical=4|PinConglomerate=56|PinLength=20|Location.X=1244|Location.Y=892|Designator=5|SwapIDPart=Ž&Ž||PinPropagationDelay=0.000000E+000
|RECORD=6|OwnerIndex=302|IsNotAccesible=T|IndexInSheet=17|OwnerPartId=1|LineWidth=1|Color=16711680|LocationCount=4|X1=1199|Y1=957|X2=1199|Y2=937|X3=1219|Y3=947|X4=1199|Y4=957
|RECORD=12|OwnerIndex=302|IsNotAccesible=T|IndexInSheet=18|OwnerPartId=1|Location.X=1209|Location.Y=954|Radius=1|Radius_Frac=79777|LineWidth=1|EndAngle=360.000|Color=16711680
|RECORD=6|OwnerIndex=302|IsNotAccesible=T|IndexInSheet=19|OwnerPartId=1|LineWidth=1|Color=16711680|LocationCount=4|X1=1219|Y1=902|X2=1219|Y2=882|X3=1199|Y3=892|X4=1219|Y4=902
|RECORD=12|OwnerIndex=302|IsNotAccesible=T|IndexInSheet=20|OwnerPartId=1|Location.X=1209|Location.Y=899|Radius=1|Radius_Frac=79777|LineWidth=1|EndAngle=360.000|Color=16711680
|RECORD=6|OwnerIndex=302|IsNotAccesible=T|IndexInSheet=21|OwnerPartId=1|LineWidth=1|Color=16711680|LocationCount=3|X1=1209|Y1=901|X2=1209|Y2=917|X3=1174|Y3=917
|RECORD=6|OwnerIndex=302|IsNotAccesible=T|IndexInSheet=22|OwnerPartId=1|LineWidth=1|Color=16711680|LocationCount=3|X1=1209|Y1=956|X2=1209|Y2=972|X3=1174|Y3=972
|RECORD=6|OwnerIndex=302|IsNotAccesible=T|IndexInSheet=23|OwnerPartId=1|LineWidth=1|Color=16711680|LocationCount=2|X1=1174|Y1=947|X2=1199|Y2=947
|RECORD=6|OwnerIndex=302|IsNotAccesible=T|IndexInSheet=24|OwnerPartId=1|LineWidth=1|Color=16711680|LocationCount=2|X1=1219|Y1=947|X2=1244|Y2=947
|RECORD=6|OwnerIndex=302|IsNotAccesible=T|IndexInSheet=25|OwnerPartId=1|LineWidth=1|Color=16711680|LocationCount=2|X1=1219|Y1=892|X2=1244|Y2=892
|RECORD=6|OwnerIndex=302|IsNotAccesible=T|IndexInSheet=26|OwnerPartId=1|LineWidth=1|Color=16711680|LocationCount=2|X1=1199|Y1=892|X2=1174|Y2=892
|RECORD=34|OwnerIndex=302|IndexInSheet=-1|OwnerPartId=-1|Location.X=1173|Location.Y=982|Color=8388608|FontID=1|Text=U11|Name=Designator|ReadOnlyState=1
|RECORD=41|OwnerIndex=302|IndexInSheet=-1|OwnerPartId=-1|Location.X=1173|Location.Y=847|Color=8388608|FontID=1|Text=NC7WV125K8X|Name=Comment
|RECORD=44|OwnerIndex=302
|RECORD=45|OwnerIndex=340|IndexInSheet=-1|ModelName=SOP50P310X90-8N|ModelType=PCBLIB|DatafileCount=1|ModelDatafile0=C:\Users\<user>\Documents\AltiumLL\SamacSys.PcbLib|ModelDatafileEntity0=SOP50P310X90-8N|ModelDatafileKind0=PCBLIB|IsCurrent=T
|RECORD=46|OwnerIndex=341
|RECORD=48|OwnerIndex=341
|RECORD=17|IndexInSheet=49|OwnerPartId=-1|Style=4|ShowNetName=T|Location.X=1464|Location.Y=817|Orientation=3|Color=128|FontID=1|Text=GND
|RECORD=1|LibReference=CN-1P-M-RF3|ComponentDescription=Ultra Miniature Coaxial Connector Jack, 60 V, 50 Ohm, -40 to 90 degC, RoHS, Tape and Reel|PartCount=2|DisplayModeCount=1|IndexInSheet=50|OwnerPartId=-1|Location.X=1394|Location.Y=967|CurrentPartId=1|LibraryPath=*|SourceLibraryName=Altium Content Vault|TargetFileName=*|AreaColor=11599871|Color=128|PartIDLocked=T|DesignItemId=CMP-2000-07505-1|AllPinCount=3
|RECORD=8|OwnerIndex=345|IsNotAccesible=T|OwnerPartId=1|Location.X=1414|Location.Y=947|Radius=20|SecondaryRadius=20|LineWidth=1|Color=16711680|AreaColor=16777215
|RECORD=8|OwnerIndex=345|IsNotAccesible=T|IndexInSheet=1|OwnerPartId=1|Location.X=1414|Location.Y=947|Radius=4|SecondaryRadius=4|LineWidth=1|Color=16711680|AreaColor=16777215
|RECORD=2|OwnerIndex=345|OwnerPartId=1|FormalType=1|Electrical=4|PinConglomerate=51|PinLength=10|Location.X=1404|Location.Y=927|Name=1|Designator=1|PinPropagationDelay=0.000000E+000
|RECORD=2|OwnerIndex=345|OwnerPartId=1|FormalType=1|Electrical=4|PinConglomerate=50|PinLength=10|Location.X=1394|Location.Y=947|Name=2|Designator=2|PinPropagationDelay=0.000000E+000
|RECORD=2|OwnerIndex=345|OwnerPartId=1|FormalType=1|Electrical=4|PinConglomerate=51|PinLength=10|Location.X=1424|Location.Y=927|Name=3|Designator=3|PinPropagationDelay=0.000000E+000
|RECORD=6|OwnerIndex=345|IsNotAccesible=T|IndexInSheet=5|OwnerPartId=1|LineWidth=1|Color=16711680|LocationCount=5|X1=1394|Y1=927|X2=1394|Y2=967|X3=1434|Y3=967|X4=1434|Y4=927|X5=1394|Y5=927
|RECORD=6|OwnerIndex=345|IsNotAccesible=T|IndexInSheet=6|OwnerPartId=1|LineWidth=1|Color=16711680|LocationCount=2|X1=1394|Y1=947|X2=1410|Y2=947
|RECORD=41|OwnerIndex=345|IndexInSheet=7|OwnerPartId=-1|Location.X=1382|Location.Y=968|Color=8388608|FontID=1|IsHidden=T|Text=Straight|Name=Orientation
|RECORD=41|OwnerIndex=345|IndexInSheet=8|OwnerPartId=-1|Location.X=1382|Location.Y=968|Color=8388608|FontID=1|IsHidden=T|Text=Female|Name=Gender
|RECORD=41|OwnerIndex=345|IndexInSheet=9|OwnerPartId=-1|Location.X=1382|Location.Y=968|Color=8388608|FontID=1|IsHidden=T|Text=Vertical|Name=PCB Mounting Orientation
|RECORD=41|OwnerIndex=345|IndexInSheet=10|OwnerPartId=-1|Location.X=1382|Location.Y=968|Color=8388608|FontID=1|IsHidden=T|Text=SurfaceMount|Name=Mount
|RECORD=41|OwnerIndex=345|IndexInSheet=11|OwnerPartId=-1|Location.X=1382|Location.Y=968|Color=8388608|FontID=1|IsHidden=T|Text=3mm|Name=Length
|RECORD=41|OwnerIndex=345|IndexInSheet=12|OwnerPartId=-1|Location.X=1382|Location.Y=968|Color=8388608|FontID=1|IsHidden=T|Text=TapeandReel|Name=Packaging
|RECORD=41|OwnerIndex=345|IndexInSheet=13|OwnerPartId=-1|Location.X=1382|Location.Y=968|Color=8388608|FontID=1|IsHidden=T|Text=Jack|Name=Connector Type
|RECORD=41|OwnerIndex=345|IndexInSheet=14|OwnerPartId=-1|Location.X=1382|Location.Y=968|Color=8388608|FontID=1|IsHidden=T|Text=LeadFree|Name=Lead Free
|RECORD=41|OwnerIndex=345|IndexInSheet=15|OwnerPartId=-1|Location.X=1382|Location.Y=968|Color=8388608|FontID=1|IsHidden=T|Text=1|Name=Package Quantity
|RECORD=41|OwnerIndex=345|IndexInSheet=16|OwnerPartId=-1|Location.X=1382|Location.Y=968|Color=8388608|FontID=1|IsHidden=T|Text=SMD/SMT|Name=Termination
|RECORD=41|OwnerIndex=345|IndexInSheet=17|OwnerPartId=-1|Location.X=1382|Location.Y=968|Color=8388608|FontID=1|IsHidden=T|Text=CopperAlloy|Name=Contact Material
|RECORD=41|OwnerIndex=345|IndexInSheet=18|OwnerPartId=-1|Location.X=1382|Location.Y=968|Color=8388608|FontID=1|IsHidden=T|Text=Pull|Name=Fastening Type
|RECORD=41|OwnerIndex=345|IndexInSheet=19|OwnerPartId=-1|Location.X=1382|Location.Y=968|Color=8388608|FontID=1|IsHidden=T|Text=true|Name=RoHSCompliant
|RECORD=41|OwnerIndex=345|IndexInSheet=20|OwnerPartId=-1|Location.X=1382|Location.Y=968|Color=8388608|FontID=1|IsHidden=T|Text=LiquidCrystalPolymer|Name=Body Material
|RECORD=41|OwnerIndex=345|IndexInSheet=21|OwnerPartId=-1|Location.X=1382|Location.Y=968|Color=8388608|FontID=1|IsHidden=T|Text=SMD/SMT|Name=Case\/Package
|RECORD=41|OwnerIndex=345|IndexInSheet=22|OwnerPartId=-1|Location.X=1382|Location.Y=968|Color=8388608|FontID=1|IsHidden=T|Text=90degC|Name=Max Operating Temperature
|RECORD=41|OwnerIndex=345|IndexInSheet=23|OwnerPartId=-1|Location.X=1382|Location.Y=968|Color=8388608|FontID=1|IsHidden=T|Text=50Ohm|Name=Impedance
|RECORD=41|OwnerIndex=345|IndexInSheet=24|OwnerPartId=-1|Location.X=1382|Location.Y=968|Color=8388608|FontID=3|IsHidden=T|Text=http://www.te.com/commerce/DocumentDelivery/DDEController?Action=srchrtrv&DocNm=1909763&DocType=Customer+Drawing&DocLang=English|Name=Datasheet URL
|RECORD=41|OwnerIndex=345|IndexInSheet=25|OwnerPartId=-1|Location.X=1382|Location.Y=968|Color=8388608|FontID=1|IsHidden=T|Text=Gold|Name=Contact Plating
|RECORD=41|OwnerIndex=345|IndexInSheet=26|OwnerPartId=-1|Location.X=1382|Location.Y=968|Color=8388608|FontID=1|IsHidden=T|Text=SurfaceMount|Name=Mounting Technology
|RECORD=41|OwnerIndex=345|IndexInSheet=27|OwnerPartId=-1|Location.X=1382|Location.Y=968|Color=8388608|FontID=1|IsHidden=T|Text=6GHz|Name=Max Frequency
|RECORD=41|OwnerIndex=345|IndexInSheet=28|OwnerPartId=-1|Location.X=1382|Location.Y=968|Color=8388608|FontID=1|IsHidden=T|Text=TECO-1909763-1|Name=Package Reference
|RECORD=41|OwnerIndex=345|IndexInSheet=29|OwnerPartId=-1|Location.X=1382|Location.Y=968|Color=8388608|FontID=1|IsHidden=T|Text=Thermoplastic|Name=Insulation Material
|RECORD=41|OwnerIndex=345|IndexInSheet=30|OwnerPartId=-1|Location.X=1382|Location.Y=968|Color=8388608|FontID=1|IsHidden=T|Text=-40degC|Name=Min Operating Temperature
|RECORD=41|OwnerIndex=345|IndexInSheet=31|OwnerPartId=-1|Location.X=1382|Location.Y=968|Color=8388608|FontID=3|IsHidden=T|Text=http://www.te.com/|Name=Manufacturer URL
|RECORD=41|OwnerIndex=345|IndexInSheet=32|OwnerPartId=-1|Location.X=1382|Location.Y=968|Color=8388608|FontID=1|IsHidden=T|Text=Gold|Name=Body Plating
|RECORD=41|OwnerIndex=345|IndexInSheet=33|OwnerPartId=-1|Location.X=1382|Location.Y=968|Color=8388608|FontID=1|IsHidden=T|Text=Polymer|Name=Dielectric Material
|RECORD=41|OwnerIndex=345|IndexInSheet=34|OwnerPartId=-1|Location.X=1382|Location.Y=968|Color=8388608|FontID=1|IsHidden=T|Text=TE Connectivity|Name=Manufacturer
|RECORD=41|OwnerIndex=345|IndexInSheet=35|OwnerPartId=-1|Location.X=1382|Location.Y=968|Color=8388608|FontID=1|IsHidden=T|Text=Compliant|Name=ELV
|RECORD=41|OwnerIndex=345|IndexInSheet=36|OwnerPartId=-1|Location.X=1382|Location.Y=968|Color=8388608|FontID=1|IsHidden=T|Text=Rev. B2, 11/2015|Name=Datasheet Version
|RECORD=41|OwnerIndex=345|IndexInSheet=37|OwnerPartId=-1|Location.X=1382|Location.Y=968|Color=8388608|FontID=1|IsHidden=T|Text=No|Name=Radiation Hardening
|RECORD=41|OwnerIndex=345|IndexInSheet=38|OwnerPartId=-1|Location.X=1382|Location.Y=968|Color=8388608|FontID=1|IsHidden=T|Text=3-Pin Surface Mount Device, Body 2.6 x 2.6 mm|Name=Package Description
|RECORD=41|OwnerIndex=345|IndexInSheet=39|OwnerPartId=-1|Location.X=1382|Location.Y=968|Color=8388608|FontID=1|IsHidden=T|Text=Beige|Name=Housing Colour
|RECORD=34|OwnerIndex=345|IndexInSheet=-1|OwnerPartId=-1|Location.X=1393|Location.Y=968|Color=8388608|FontID=1|Text=J3|Name=Designator|ReadOnlyState=1
|RECORD=41|OwnerIndex=345|IndexInSheet=-1|OwnerPartId=-1|Location.X=1444|Location.Y=927|Color=8388608|FontID=1|Text=1909763-1|Name=Comment
|RECORD=44|OwnerIndex=345
|RECORD=45|OwnerIndex=391|IndexInSheet=-1|Description=SMD, 3-Leads, Body 2.6x2.6mm, Height 1.25mm|UseComponentLibrary=T|ModelName=TECO-1909763-1_V|ModelType=PCBLIB|DatafileCount=1|ModelDatafileEntity0=TECO-1909763-1_V|ModelDatafileKind0=PCBLib|IsCurrent=T|DatalinksLocked=T|DatabaseDatalinksLocked=T
|RECORD=46|OwnerIndex=392
|RECORD=48|OwnerIndex=392
|RECORD=41|OwnerIndex=394|IndexInSheet=-1|OwnerPartId=-1|Color=8388608|FontID=1|Text=2D|Name=Available Preview Images
|RECORD=1|LibReference=CN-S-4F-RF5|ComponentDescription=Coaxial connector, 50 Ohm, -65 to 165 degC, 5-Pin THD, RoHS, Bulk|PartCount=2|DisplayModeCount=1|IndexInSheet=51|OwnerPartId=-1|Location.X=1394|Location.Y=887|CurrentPartId=1|LibraryPath=*|SourceLibraryName=Altium Content Vault|TargetFileName=*|AreaColor=11599871|Color=128|PartIDLocked=T|DesignItemId=CMP-2000-05705-1|AllPinCount=5
|RECORD=2|OwnerIndex=396|OwnerPartId=1|FormalType=1|Electrical=4|PinConglomerate=51|PinLength=10|Location.X=1434|Location.Y=847|Name=5|Designator=5|SwapIDPart=Ž&Ž1|PinPropagationDelay=0.000000E+000
|RECORD=8|OwnerIndex=396|IsNotAccesible=T|IndexInSheet=1|OwnerPartId=1|Location.X=1414|Location.Y=867|Radius=20|SecondaryRadius=20|LineWidth=1|Color=16711680|AreaColor=16777215
|RECORD=8|OwnerIndex=396|IsNotAccesible=T|IndexInSheet=2|OwnerPartId=1|Location.X=1414|Location.Y=867|Radius=4|SecondaryRadius=4|LineWidth=1|Color=16711680|AreaColor=16777215
|RECORD=2|OwnerIndex=396|OwnerPartId=1|FormalType=1|Electrical=4|PinConglomerate=50|PinLength=10|Location.X=1394|Location.Y=867|Name=1|Designator=1|PinPropagationDelay=0.000000E+000
|RECORD=2|OwnerIndex=396|OwnerPartId=1|FormalType=1|Electrical=4|PinConglomerate=51|PinLength=10|Location.X=1404|Location.Y=847|Name=2|Designator=2|PinPropagationDelay=0.000000E+000
|RECORD=2|OwnerIndex=396|OwnerPartId=1|FormalType=1|Electrical=4|PinConglomerate=51|PinLength=10|Location.X=1414|Location.Y=847|Name=3|Designator=3|PinPropagationDelay=0.000000E+000
|RECORD=2|OwnerIndex=396|OwnerPartId=1|FormalType=1|Electrical=4|PinConglomerate=51|PinLength=10|Location.X=1424|Location.Y=847|Name=4|Designator=4|PinPropagationDelay=0.000000E+000
|RECORD=6|OwnerIndex=396|IsNotAccesible=T|IndexInSheet=7|OwnerPartId=1|LineWidth=1|Color=16711680|LocationCount=5|X1=1394|Y1=847|X2=1394|Y2=887|X3=1434|Y3=887|X4=1434|Y4=847|X5=1394|Y5=847
|RECORD=6|OwnerIndex=396|IsNotAccesible=T|IndexInSheet=8|OwnerPartId=1|LineWidth=1|Color=16711680|LocationCount=2|X1=1394|Y1=867|X2=1410|Y2=867
|RECORD=41|OwnerIndex=396|IndexInSheet=9|OwnerPartId=-1|Location.X=1382|Location.Y=888|Color=8388608|FontID=1|IsHidden=T|Text=ThroughHole|Name=Mounting Technology
|RECORD=41|OwnerIndex=396|IndexInSheet=10|OwnerPartId=-1|Location.X=1382|Location.Y=888|Color=8388608|FontID=1|IsHidden=T|Text=ThroughHole,RightAngle|Name=Mounting Type
|RECORD=41|OwnerIndex=396|IndexInSheet=11|OwnerPartId=-1|Location.X=1382|Location.Y=888|Color=8388608|FontID=1|IsHidden=T|Text=-|Name=Cable Group
|RECORD=41|OwnerIndex=396|IndexInSheet=12|OwnerPartId=-1|Location.X=1382|Location.Y=888|Color=8388608|FontID=1|IsHidden=T|Text=901-143-6RFXMountingHole|Name=Catalog Drawings
|RECORD=41|OwnerIndex=396|IndexInSheet=13|OwnerPartId=-1|Location.X=1382|Location.Y=888|Color=8388608|FontID=1|IsHidden=T|Text=901-143-6RFX.igs|Name=3D Model
|RECORD=41|OwnerIndex=396|IndexInSheet=14|OwnerPartId=-1|Location.X=1382|Location.Y=888|Color=8388608|FontID=1|IsHidden=T|Text=-|Name=Series
|RECORD=41|OwnerIndex=396|IndexInSheet=15|OwnerPartId=-1|Location.X=1382|Location.Y=888|Color=8388608|FontID=1|IsHidden=T|Text=5-Pin Through Hole Device, Body 7 x 7 mm, Pitch 2.54 mm|Name=Package Description
|RECORD=41|OwnerIndex=396|IndexInSheet=16|OwnerPartId=-1|Location.X=1382|Location.Y=888|Color=8388608|FontID=1|IsHidden=T|Text=901-143-6RFX|Name=Package Reference
|RECORD=41|OwnerIndex=396|IndexInSheet=17|OwnerPartId=-1|Location.X=1382|Location.Y=888|Color=8388608|FontID=1|IsHidden=T|Text=Brass|Name=Body Material
|RECORD=41|OwnerIndex=396|IndexInSheet=18|OwnerPartId=-1|Location.X=1382|Location.Y=888|Color=8388608|FontID=1|IsHidden=T|Text=-|Name=Voltage Rating
|RECORD=41|OwnerIndex=396|IndexInSheet=19|OwnerPartId=-1|Location.X=1382|Location.Y=888|Color=8388608|FontID=1|IsHidden=T|Text=1|Name=Standard Package
|RECORD=41|OwnerIndex=396|IndexInSheet=20|OwnerPartId=-1|Location.X=1382|Location.Y=888|Color=8388608|FontID=1|IsHidden=T|Text=Jack,FemaleSocket|Name=Connector Type
|RECORD=41|OwnerIndex=396|IndexInSheet=21|OwnerPartId=-1|Location.X=1382|Location.Y=888|Color=8388608|FontID=1|IsHidden=T|Text=Threaded|Name=Fastening Type
|RECORD=41|OwnerIndex=396|IndexInSheet=22|OwnerPartId=-1|Location.X=1382|Location.Y=888|Color=8388608|FontID=1|IsHidden=T|Text=Gold|Name=Housing Color
|RECORD=41|OwnerIndex=396|IndexInSheet=23|OwnerPartId=-1|Location.X=1382|Location.Y=888|Color=8388608|FontID=1|IsHidden=T|Text=Solder|Name=Shield Termination
|RECORD=41|OwnerIndex=396|IndexInSheet=24|OwnerPartId=-1|Location.X=1382|Location.Y=888|Color=8388608|FontID=1|IsHidden=T|Text=901-143-6-RFX9011436RFXARFX1232|Name=Other Names
|RECORD=41|OwnerIndex=396|IndexInSheet=25|OwnerPartId=-1|Location.X=1382|Location.Y=888|Color=8388608|FontID=3|IsHidden=T|Text=http://www.amphenolrf.com/downloads/dl/file/id/2712/product/3102/901_143_6rfx_customer_drawing.pdf|Name=Datasheet URL
|RECORD=41|OwnerIndex=396|IndexInSheet=26|OwnerPartId=-1|Location.X=1382|Location.Y=888|Color=8388608|FontID=1|IsHidden=T|Text=CoaxialConnectors(RF)|Name=Family
|RECORD=41|OwnerIndex=396|IndexInSheet=27|OwnerPartId=-1|Location.X=1382|Location.Y=888|Color=8388608|FontID=1|IsHidden=T|Text=SMA,RFX|Name=Online Catalog
|RECORD=41|OwnerIndex=396|IndexInSheet=28|OwnerPartId=-1|Location.X=1382|Location.Y=888|Color=8388608|FontID=1|IsHidden=T|Text=18GHz|Name=Frequency - Max
|RECORD=41|OwnerIndex=396|IndexInSheet=29|OwnerPartId=-1|Location.X=1382|Location.Y=888|Color=8388608|FontID=1|IsHidden=T|Text=Solder|Name=Contact Termination
|RECORD=41|OwnerIndex=396|IndexInSheet=30|OwnerPartId=-1|Location.X=1382|Location.Y=888|Color=8388608|FontID=3|IsHidden=T|Text=http://www.amphenol.com/|Name=Manufacturer URL
|RECORD=41|OwnerIndex=396|IndexInSheet=31|OwnerPartId=-1|Location.X=1382|Location.Y=888|Color=8388608|FontID=1|IsHidden=T|Text=Amphenol|Name=Manufacturer
|RECORD=41|OwnerIndex=396|IndexInSheet=32|OwnerPartId=-1|Location.X=1382|Location.Y=888|Color=8388608|FontID=1|IsHidden=T|Text=-65°C~165°C|Name=Operating Temperature
|RECORD=41|OwnerIndex=396|IndexInSheet=33|OwnerPartId=-1|Location.X=1382|Location.Y=888|Color=8388608|FontID=1|IsHidden=T|Text=Connectors,Interconnects|Name=Category
|RECORD=41|OwnerIndex=396|IndexInSheet=34|OwnerPartId=-1|Location.X=1382|Location.Y=888|Color=8388608|FontID=1|IsHidden=T|Text=Bulk|Name=Packaging
|RECORD=41|OwnerIndex=396|IndexInSheet=35|OwnerPartId=-1|Location.X=1382|Location.Y=888|Color=8388608|FontID=1|IsHidden=T|Text=Gold|Name=Body Finish
|RECORD=41|OwnerIndex=396|IndexInSheet=36|OwnerPartId=-1|Location.X=1382|Location.Y=888|Color=8388608|FontID=1|IsHidden=T|Text=Polytetrafluoroethylene(PTFE)|Name=Dielectric Material
|RECORD=41|OwnerIndex=396|IndexInSheet=37|OwnerPartId=-1|Location.X=1382|Location.Y=888|Color=8388608|FontID=1|IsHidden=T|Text=BerylliumCopper|Name=Center Contact Material
|RECORD=41|OwnerIndex=396|IndexInSheet=38|OwnerPartId=-1|Location.X=1382|Location.Y=888|Color=8388608|FontID=1|IsHidden=T|Text=50Ohm|Name=Impedance
|RECORD=41|OwnerIndex=396|IndexInSheet=39|OwnerPartId=-1|Location.X=1382|Location.Y=888|Color=8388608|FontID=1|IsHidden=T|Text=-|Name=Features
|RECORD=41|OwnerIndex=396|IndexInSheet=40|OwnerPartId=-1|Location.X=1382|Location.Y=888|Color=8388608|FontID=1|IsHidden=T|Text=SMA|Name=Connector Style
|RECORD=41|OwnerIndex=396|IndexInSheet=41|OwnerPartId=-1|Location.X=1382|Location.Y=888|Color=8388608|FontID=1|IsHidden=T|Text=Gold|Name=Center Contact Plating
|RECORD=41|OwnerIndex=396|IndexInSheet=42|OwnerPartId=-1|Location.X=1382|Location.Y=888|Color=8388608|FontID=1|IsHidden=T|Text=Rev. C, 06/2010|Name=Datasheet Version
|RECORD=41|OwnerIndex=396|IndexInSheet=43|OwnerPartId=-1|Location.X=1382|Location.Y=888|Color=8388608|FontID=1|IsHidden=T|Text=-|Name=Ingress Protection
|RECORD=34|OwnerIndex=396|IndexInSheet=-1|OwnerPartId=-1|Location.X=1393|Location.Y=888|Color=8388608|FontID=1|Text=AN3|Name=Designator|ReadOnlyState=1
|RECORD=41|OwnerIndex=396|IndexInSheet=-1|OwnerPartId=-1|Location.X=1444|Location.Y=837|Color=8388608|FontID=1|Text=RF2-49B-T-00-50-G-HDW|Name=Comment
|RECORD=44|OwnerIndex=396
|RECORD=45|OwnerIndex=448|IndexInSheet=-1|Description=THD, 5-Leads, Body 7x7mm, Pitch 2.54mm|UseComponentLibrary=T|ModelName=AMPH-901-143-6RFX_V|ModelType=PCBLIB|DatafileCount=1|ModelDatafileEntity0=AMPH-901-143-6RFX_V|ModelDatafileKind0=PCBLib|IsCurrent=T|DatalinksLocked=T|DatabaseDatalinksLocked=T
|RECORD=46|OwnerIndex=449
|RECORD=48|OwnerIndex=449
|RECORD=41|OwnerIndex=451|IndexInSheet=-1|OwnerPartId=-1|Color=8388608|FontID=1|Text=2D|Name=Available Preview Images
|RECORD=17|IndexInSheet=52|OwnerPartId=-1|Style=4|ShowNetName=T|Location.X=1464|Location.Y=907|Orientation=3|Color=128|FontID=1|Text=GND
|RECORD=1|LibReference=RES-2|ComponentDescription=General Purpose Chip Resistor, 49.9 Ohm, +/- 1%, -55 to 155 degC, 0603 (1608 Metric), RoHS, Tape and Reel|PartCount=2|DisplayModeCount=1|IndexInSheet=53|OwnerPartId=-1|Location.X=1299|Location.Y=947|CurrentPartId=1|LibraryPath=*|SourceLibraryName=Altium Content Vault|TargetFileName=*|AreaColor=11599871|Color=128|PartIDLocked=T|DesignItemId=CMP-1659-00036-1|AllPinCount=2
|RECORD=2|OwnerIndex=454|OwnerPartId=1|FormalType=1|Electrical=4|PinConglomerate=32|PinLength=10|Location.X=1319|Location.Y=947|Name=2|Designator=2|PinPropagationDelay=0.000000E+000
|RECORD=2|OwnerIndex=454|OwnerPartId=1|FormalType=1|Electrical=4|PinConglomerate=34|PinLength=10|Location.X=1299|Location.Y=947|Name=1|Designator=1|PinPropagationDelay=0.000000E+000
|RECORD=6|OwnerIndex=454|IsNotAccesible=T|IndexInSheet=2|OwnerPartId=1|LineWidth=1|Color=16711680|LocationCount=10|X1=1319|Y1=947|X2=1315|Y2=947|X3=1314|Y3=945|X4=1312|Y4=949|X5=1310|Y5=945|X6=1308|Y6=949|X7=1306|Y7=945|X8=1304|Y8=949|X9=1303|Y9=947|X10=1299|Y10=947
|RECORD=41|OwnerIndex=454|IndexInSheet=3|OwnerPartId=-1|Location.X=1287|Location.Y=962|Color=8388608|FontID=1|IsHidden=T|Text=0603|Name=PackageReference
|RECORD=41|OwnerIndex=454|IndexInSheet=4|OwnerPartId=-1|Location.X=1287|Location.Y=962|Color=8388608|FontID=1|IsHidden=T|Text=Tray|Name=Packaging
|RECORD=41|OwnerIndex=454|IndexInSheet=5|OwnerPartId=-1|Location.X=1287|Location.Y=962|Color=8388608|FontID=1|IsHidden=T|Text=Datasheet|Name=ComponentLink2Description
|RECORD=41|OwnerIndex=454|IndexInSheet=6|OwnerPartId=-1|Location.X=1287|Location.Y=962|Color=8388608|FontID=1|IsHidden=T|Text=Manufacturer URL|Name=ComponentLink1Description
|RECORD=41|OwnerIndex=454|IndexInSheet=7|OwnerPartId=-1|Location.X=1287|Location.Y=962|Color=8388608|FontID=3|IsHidden=T|Text=https://datasheet.ciiva.com/11808/0900766b80f96399-11808223.pdf|Name=ComponentLink2URL
|RECORD=41|OwnerIndex=454|IndexInSheet=8|OwnerPartId=-1|Location.X=1287|Location.Y=962|Color=8388608|FontID=1|IsHidden=T|Text=true|Name=RoHSCompliant
|RECORD=41|OwnerIndex=454|IndexInSheet=9|OwnerPartId=-1|Location.X=1287|Location.Y=962|Color=8388608|FontID=1|IsHidden=T|Text=85 degC|Name=Max Operating Temperature
|RECORD=41|OwnerIndex=454|IndexInSheet=10|OwnerPartId=-1|Location.X=1287|Location.Y=962|Color=8388608|FontID=1|IsHidden=T|Text=3.63 V|Name=Max Supply Voltage
|RECORD=41|OwnerIndex=454|IndexInSheet=11|OwnerPartId=-1|Location.X=1287|Location.Y=962|Color=8388608|FontID=3|IsHidden=T|Text=http://www.yageo.com/|Name=ComponentLink1URL
|RECORD=41|OwnerIndex=454|IndexInSheet=12|OwnerPartId=-1|Location.X=1287|Location.Y=962|Color=8388608|FontID=1|IsHidden=T|Text=2-Pin Surface Mount Device, Body 1.6 x 0.8 mm|Name=PackageDescription
|RECORD=41|OwnerIndex=454|IndexInSheet=13|OwnerPartId=-1|Location.X=1287|Location.Y=962|Color=8388608|FontID=1|IsHidden=T|Text=LQFP|Name=Case\Package
|RECORD=41|OwnerIndex=454|IndexInSheet=14|OwnerPartId=-1|Location.X=1287|Location.Y=962|Color=8388608|FontID=1|IsHidden=T|Text=Rev. 4, 04/2009|Name=DatasheetVersion
|RECORD=41|OwnerIndex=454|IndexInSheet=15|OwnerPartId=-1|Location.X=1287|Location.Y=962|Color=8388608|FontID=1|IsHidden=T|Text=-40 degC|Name=Min Operating Temperature
|RECORD=41|OwnerIndex=454|IndexInSheet=16|OwnerPartId=-1|Location.X=1287|Location.Y=962|Color=8388608|FontID=1|IsHidden=T|Text=SPI|Name=Interface
|RECORD=41|OwnerIndex=454|IndexInSheet=17|OwnerPartId=-1|Location.X=1287|Location.Y=962|Color=8388608|FontID=1|IsHidden=T|Text=250|Name=Package Quantity
|RECORD=41|OwnerIndex=454|IndexInSheet=18|OwnerPartId=-1|Location.X=1287|Location.Y=962|Color=8388608|FontID=1|IsHidden=T|Text=2.97 V|Name=Min Supply Voltage
|RECORD=41|OwnerIndex=454|IndexInSheet=19|OwnerPartId=-1|Location.X=1287|Location.Y=962|Color=8388608|FontID=1|IsHidden=T|Text=48|Name=Pins
|RECORD=34|OwnerIndex=454|IndexInSheet=-1|OwnerPartId=-1|Location.X=1298|Location.Y=950|Color=8388608|FontID=1|Text=R28|Name=Designator|ReadOnlyState=1
|RECORD=41|OwnerIndex=454|IndexInSheet=-1|OwnerPartId=-1|Location.X=1298|Location.Y=934|Color=8388608|FontID=1|Text=49.9R|Name=Comment
|RECORD=44|OwnerIndex=454
|RECORD=45|OwnerIndex=479|IndexInSheet=-1|Description=Chip Resistor, 2-Leads, Body 1.70x0.90mm, IPC Medium Density|UseComponentLibrary=T|ModelName=RESC1608X55X25NL10T15|ModelType=PCBLIB|DatafileCount=1|ModelDatafileEntity0=RESC1608X55X25NL10T15|ModelDatafileKind0=PCBLib|IsCurrent=T|DatalinksLocked=T|DatabaseDatalinksLocked=T
|RECORD=46|OwnerIndex=480
|RECORD=48|OwnerIndex=480
|RECORD=41|OwnerIndex=482|IndexInSheet=-1|OwnerPartId=-1|Color=8388608|FontID=1|IsHidden=T|Text=2D|Name=Available Preview Images
|RECORD=45|OwnerIndex=479|IndexInSheet=-1|Description=Chip Resistor, 2-Leads, Body 1.70x0.90mm, IPC Low Density|UseComponentLibrary=T|ModelName=RESC1608X55X25ML10T15|ModelType=PCBLIB|DatafileCount=1|ModelDatafileEntity0=RESC1608X55X25ML10T15|ModelDatafileKind0=PCBLib|DatalinksLocked=T|DatabaseDatalinksLocked=T
|RECORD=46|OwnerIndex=484
|RECORD=48|OwnerIndex=484
|RECORD=41|OwnerIndex=486|IndexInSheet=-1|OwnerPartId=-1|Color=8388608|FontID=1|IsHidden=T|Text=2D|Name=Available Preview Images
|RECORD=45|OwnerIndex=479|IndexInSheet=-1|Description=Chip Resistor, 2-Leads, Body 1.70x0.90mm, IPC High Density|UseComponentLibrary=T|ModelName=RESC1608X55X25LL10T15|ModelType=PCBLIB|DatafileCount=1|ModelDatafileEntity0=RESC1608X55X25LL10T15|ModelDatafileKind0=PCBLib|DatalinksLocked=T|DatabaseDatalinksLocked=T
|RECORD=46|OwnerIndex=488
|RECORD=48|OwnerIndex=488
|RECORD=41|OwnerIndex=490|IndexInSheet=-1|OwnerPartId=-1|Color=8388608|FontID=1|IsHidden=T|Text=2D|Name=Available Preview Images
|RECORD=17|IndexInSheet=54|OwnerPartId=-1|ShowNetName=T|Location.X=1024|Location.Y=947|Orientation=2|Color=255|FontID=1|Text=ANT3_OUT|IsCrossSheetConnector=T
|RECORD=17|IndexInSheet=55|OwnerPartId=-1|ShowNetName=T|Location.X=1030|Location.Y=1060|Orientation=1|Color=128|FontID=1|Text=+3.3V
|RECORD=17|IndexInSheet=56|OwnerPartId=-1|ShowNetName=T|Location.X=1060|Location.Y=1060|Orientation=1|Color=128|FontID=1|Text=+3.3V
|RECORD=17|IndexInSheet=57|OwnerPartId=-1|ShowNetName=T|Location.X=1024|Location.Y=892|Orientation=2|Color=255|FontID=1|Text=ANT3_IN|IsCrossSheetConnector=T
|RECORD=17|IndexInSheet=58|OwnerPartId=-1|Style=4|ShowNetName=T|Location.X=1144|Location.Y=817|Orientation=3|Color=128|FontID=1|Text=GND
|RECORD=17|IndexInSheet=59|OwnerPartId=-1|Style=4|ShowNetName=T|Location.X=1094|Location.Y=817|Orientation=3|Color=128|FontID=1|Text=GND
|RECORD=17|IndexInSheet=60|OwnerPartId=-1|ShowNetName=T|Location.X=1094|Location.Y=1037|Orientation=1|Color=128|FontID=1|Text=+3.3V
|RECORD=1|LibReference=NC7WV125K8X|ComponentDescription=Integrated Circuit|PartCount=2|DisplayModeCount=1|IndexInSheet=61|OwnerPartId=-1|Location.X=1154|Location.Y=552|CurrentPartId=1|LibraryPath=*|SourceLibraryName=SamacSys.SchLib|TargetFileName=*|AreaColor=11599871|Color=128|PartIDLocked=T|DesignItemId=NC7WV125K8X|AllPinCount=8
|RECORD=41|OwnerIndex=499|OwnerPartId=-1|Location.X=1154|Location.Y=552|Color=8388608|FontID=3|IsHidden=T|Text=https://www.mouser.com/datasheet/2/308/NC7WV125-1301459.pdf|Name=Datasheet Link
|RECORD=41|OwnerIndex=499|IndexInSheet=1|OwnerPartId=-1|Location.X=1154|Location.Y=552|Color=8388608|FontID=1|IsHidden=T|Text=0.9mm|Name=Height
|RECORD=41|OwnerIndex=499|IndexInSheet=2|OwnerPartId=-1|Location.X=1154|Location.Y=552|Color=8388608|FontID=1|IsHidden=T|Text=ON Semiconductor|Name=Manufacturer_Name
|RECORD=41|OwnerIndex=499|IndexInSheet=3|OwnerPartId=-1|Location.X=1154|Location.Y=552|Color=8388608|FontID=1|IsHidden=T|Text=NC7WV125K8X|Name=Manufacturer_Part_Number
|RECORD=41|OwnerIndex=499|IndexInSheet=4|OwnerPartId=-1|Location.X=1154|Location.Y=552|Color=8388608|FontID=1|IsHidden=T|Text=512-NC7WV125K8X|Name=Mouser Part Number
|RECORD=41|OwnerIndex=499|IndexInSheet=5|OwnerPartId=-1|Location.X=1154|Location.Y=552|Color=8388608|FontID=3|IsHidden=T|Text=https://www.mouser.com/Search/Refine.aspx?Keyword=512-NC7WV125K8X|Name=Mouser Price/Stock
|RECORD=41|OwnerIndex=499|IndexInSheet=6|OwnerPartId=-1|Location.X=1154|Location.Y=552|Color=8388608|FontID=1|IsHidden=T|Text=NC7WV125K8X|Name=Arrow Part Number
|RECORD=41|OwnerIndex=499|IndexInSheet=7|OwnerPartId=-1|Location.X=1154|Location.Y=552|Color=8388608|FontID=3|IsHidden=T|Text=https://www.arrow.com/en/products/nc7wv125k8x/on-semiconductor|Name=Arrow Price/Stock
|RECORD=14|OwnerIndex=499|IsNotAccesible=T|IndexInSheet=8|OwnerPartId=1|Location.X=1174|Location.Y=527|Corner.X=1244|Corner.Y=652|LineWidth=1|Color=128|AreaColor=11599871|IsSolid=T
|RECORD=2|OwnerIndex=499|OwnerPartId=1|FormalType=1|Electrical=4|PinConglomerate=58|PinLength=20|Location.X=1174|Location.Y=642|Designator=1|SwapIDPart=Ž&Ž||PinPropagationDelay=0.000000E+000
|RECORD=2|OwnerIndex=499|OwnerPartId=1|FormalType=1|Electrical=4|PinConglomerate=58|PinLength=20|Location.X=1174|Location.Y=617|Designator=2|SwapIDPart=Ž&Ž||PinPropagationDelay=0.000000E+000
|RECORD=2|OwnerIndex=499|OwnerPartId=1|FormalType=1|Electrical=4|PinConglomerate=58|PinLength=20|Location.X=1174|Location.Y=562|Designator=3|SwapIDPart=Ž&Ž||PinPropagationDelay=0.000000E+000
|RECORD=2|OwnerIndex=499|OwnerPartId=1|FormalType=1|Electrical=4|PinConglomerate=58|PinLength=20|Location.X=1174|Location.Y=532|Name=GND|Designator=4|SwapIDPart=Ž&Ž||PinPropagationDelay=0.000000E+000
|RECORD=2|OwnerIndex=499|OwnerPartId=1|FormalType=1|Electrical=4|PinConglomerate=58|PinLength=20|Location.X=1174|Location.Y=542|Name=VCC|Designator=8|SwapIDPart=Ž&Ž||PinPropagationDelay=0.000000E+000
|RECORD=2|OwnerIndex=499|OwnerPartId=1|FormalType=1|Electrical=4|PinConglomerate=58|PinLength=20|Location.X=1174|Location.Y=587|Designator=7|SwapIDPart=Ž&Ž||PinPropagationDelay=0.000000E+000
|RECORD=2|OwnerIndex=499|OwnerPartId=1|FormalType=1|Electrical=4|PinConglomerate=56|PinLength=20|Location.X=1244|Location.Y=617|Designator=6|SwapIDPart=Ž&Ž||PinPropagationDelay=0.000000E+000
|RECORD=2|OwnerIndex=499|OwnerPartId=1|FormalType=1|Electrical=4|PinConglomerate=56|PinLength=20|Location.X=1244|Location.Y=562|Designator=5|SwapIDPart=Ž&Ž||PinPropagationDelay=0.000000E+000
|RECORD=6|OwnerIndex=499|IsNotAccesible=T|IndexInSheet=17|OwnerPartId=1|LineWidth=1|Color=16711680|LocationCount=4|X1=1199|Y1=627|X2=1199|Y2=607|X3=1219|Y3=617|X4=1199|Y4=627
|RECORD=12|OwnerIndex=499|IsNotAccesible=T|IndexInSheet=18|OwnerPartId=1|Location.X=1209|Location.Y=624|Radius=1|Radius_Frac=79777|LineWidth=1|EndAngle=360.000|Color=16711680
|RECORD=6|OwnerIndex=499|IsNotAccesible=T|IndexInSheet=19|OwnerPartId=1|LineWidth=1|Color=16711680|LocationCount=4|X1=1219|Y1=572|X2=1219|Y2=552|X3=1199|Y3=562|X4=1219|Y4=572
|RECORD=12|OwnerIndex=499|IsNotAccesible=T|IndexInSheet=20|OwnerPartId=1|Location.X=1209|Location.Y=569|Radius=1|Radius_Frac=79777|LineWidth=1|EndAngle=360.000|Color=16711680
|RECORD=6|OwnerIndex=499|IsNotAccesible=T|IndexInSheet=21|OwnerPartId=1|LineWidth=1|Color=16711680|LocationCount=3|X1=1209|Y1=571|X2=1209|Y2=587|X3=1174|Y3=587
|RECORD=6|OwnerIndex=499|IsNotAccesible=T|IndexInSheet=22|OwnerPartId=1|LineWidth=1|Color=16711680|LocationCount=3|X1=1209|Y1=626|X2=1209|Y2=642|X3=1174|Y3=642
|RECORD=6|OwnerIndex=499|IsNotAccesible=T|IndexInSheet=23|OwnerPartId=1|LineWidth=1|Color=16711680|LocationCount=2|X1=1174|Y1=617|X2=1199|Y2=617
|RECORD=6|OwnerIndex=499|IsNotAccesible=T|IndexInSheet=24|OwnerPartId=1|LineWidth=1|Color=16711680|LocationCount=2|X1=1219|Y1=617|X2=1244|Y2=617
|RECORD=6|OwnerIndex=499|IsNotAccesible=T|IndexInSheet=25|OwnerPartId=1|LineWidth=1|Color=16711680|LocationCount=2|X1=1219|Y1=562|X2=1244|Y2=562
|RECORD=6|OwnerIndex=499|IsNotAccesible=T|IndexInSheet=26|OwnerPartId=1|LineWidth=1|Color=16711680|LocationCount=2|X1=1199|Y1=562|X2=1174|Y2=562
|RECORD=34|OwnerIndex=499|IndexInSheet=-1|OwnerPartId=-1|Location.X=1173|Location.Y=652|Color=8388608|FontID=1|Text=U16|Name=Designator|ReadOnlyState=1
|RECORD=41|OwnerIndex=499|IndexInSheet=-1|OwnerPartId=-1|Location.X=1173|Location.Y=517|Color=8388608|FontID=1|Text=NC7WV125K8X|Name=Comment
|RECORD=44|OwnerIndex=499
|RECORD=45|OwnerIndex=537|IndexInSheet=-1|ModelName=SOP50P310X90-8N|ModelType=PCBLIB|DatafileCount=1|ModelDatafile0=C:\Users\<user>\Documents\AltiumLL\SamacSys.PcbLib|ModelDatafileEntity0=SOP50P310X90-8N|ModelDatafileKind0=PCBLIB|IsCurrent=T
|RECORD=46|OwnerIndex=538
|RECORD=48|OwnerIndex=538
|RECORD=1|LibReference=CN-1P-M-RF3|ComponentDescription=Ultra Miniature Coaxial Connector Jack, 60 V, 50 Ohm, -40 to 90 degC, RoHS, Tape and Reel|PartCount=2|DisplayModeCount=1|IndexInSheet=62|OwnerPartId=-1|Location.X=1394|Location.Y=637|CurrentPartId=1|LibraryPath=*|SourceLibraryName=Altium Content Vault|TargetFileName=*|AreaColor=11599871|Color=128|PartIDLocked=T|DesignItemId=CMP-2000-07505-1|AllPinCount=3
|RECORD=8|OwnerIndex=541|IsNotAccesible=T|OwnerPartId=1|Location.X=1414|Location.Y=617|Radius=20|SecondaryRadius=20|LineWidth=1|Color=16711680|AreaColor=16777215
|RECORD=8|OwnerIndex=541|IsNotAccesible=T|IndexInSheet=1|OwnerPartId=1|Location.X=1414|Location.Y=617|Radius=4|SecondaryRadius=4|LineWidth=1|Color=16711680|AreaColor=16777215
|RECORD=2|OwnerIndex=541|OwnerPartId=1|FormalType=1|Electrical=4|PinConglomerate=51|PinLength=10|Location.X=1404|Location.Y=597|Name=1|Designator=1|PinPropagationDelay=0.000000E+000
|RECORD=2|OwnerIndex=541|OwnerPartId=1|FormalType=1|Electrical=4|PinConglomerate=50|PinLength=10|Location.X=1394|Location.Y=617|Name=2|Designator=2|PinPropagationDelay=0.000000E+000
|RECORD=2|OwnerIndex=541|OwnerPartId=1|FormalType=1|Electrical=4|PinConglomerate=51|PinLength=10|Location.X=1424|Location.Y=597|Name=3|Designator=3|PinPropagationDelay=0.000000E+000
|RECORD=6|OwnerIndex=541|IsNotAccesible=T|IndexInSheet=5|OwnerPartId=1|LineWidth=1|Color=16711680|LocationCount=5|X1=1394|Y1=597|X2=1394|Y2=637|X3=1434|Y3=637|X4=1434|Y4=597|X5=1394|Y5=597
|RECORD=6|OwnerIndex=541|IsNotAccesible=T|IndexInSheet=6|OwnerPartId=1|LineWidth=1|Color=16711680|LocationCount=2|X1=1394|Y1=617|X2=1410|Y2=617
|RECORD=41|OwnerIndex=541|IndexInSheet=7|OwnerPartId=-1|Location.X=1382|Location.Y=638|Color=8388608|FontID=1|IsHidden=T|Text=Straight|Name=Orientation
|RECORD=41|OwnerIndex=541|IndexInSheet=8|OwnerPartId=-1|Location.X=1382|Location.Y=638|Color=8388608|FontID=1|IsHidden=T|Text=Female|Name=Gender
|RECORD=41|OwnerIndex=541|IndexInSheet=9|OwnerPartId=-1|Location.X=1382|Location.Y=638|Color=8388608|FontID=1|IsHidden=T|Text=Vertical|Name=PCB Mounting Orientation
|RECORD=41|OwnerIndex=541|IndexInSheet=10|OwnerPartId=-1|Location.X=1382|Location.Y=638|Color=8388608|FontID=1|IsHidden=T|Text=SurfaceMount|Name=Mount
|RECORD=41|OwnerIndex=541|IndexInSheet=11|OwnerPartId=-1|Location.X=1382|Location.Y=638|Color=8388608|FontID=1|IsHidden=T|Text=3mm|Name=Length
|RECORD=41|OwnerIndex=541|IndexInSheet=12|OwnerPartId=-1|Location.X=1382|Location.Y=638|Color=8388608|FontID=1|IsHidden=T|Text=TapeandReel|Name=Packaging
|RECORD=41|OwnerIndex=541|IndexInSheet=13|OwnerPartId=-1|Location.X=1382|Location.Y=638|Color=8388608|FontID=1|IsHidden=T|Text=Jack|Name=Connector Type
|RECORD=41|OwnerIndex=541|IndexInSheet=14|OwnerPartId=-1|Location.X=1382|Location.Y=638|Color=8388608|FontID=1|IsHidden=T|Text=LeadFree|Name=Lead Free
|RECORD=41|OwnerIndex=541|IndexInSheet=15|OwnerPartId=-1|Location.X=1382|Location.Y=638|Color=8388608|FontID=1|IsHidden=T|Text=1|Name=Package Quantity
|RECORD=41|OwnerIndex=541|IndexInSheet=16|OwnerPartId=-1|Location.X=1382|Location.Y=638|Color=8388608|FontID=1|IsHidden=T|Text=SMD/SMT|Name=Termination
|RECORD=41|OwnerIndex=541|IndexInSheet=17|OwnerPartId=-1|Location.X=1382|Location.Y=638|Color=8388608|FontID=1|IsHidden=T|Text=CopperAlloy|Name=Contact Material
|RECORD=41|OwnerIndex=541|IndexInSheet=18|OwnerPartId=-1|Location.X=1382|Location.Y=638|Color=8388608|FontID=1|IsHidden=T|Text=Pull|Name=Fastening Type
|RECORD=41|OwnerIndex=541|IndexInSheet=19|OwnerPartId=-1|Location.X=1382|Location.Y=638|Color=8388608|FontID=1|IsHidden=T|Text=true|Name=RoHSCompliant
|RECORD=41|OwnerIndex=541|IndexInSheet=20|OwnerPartId=-1|Location.X=1382|Location.Y=638|Color=8388608|FontID=1|IsHidden=T|Text=LiquidCrystalPolymer|Name=Body Material
|RECORD=41|OwnerIndex=541|IndexInSheet=21|OwnerPartId=-1|Location.X=1382|Location.Y=638|Color=8388608|FontID=1|IsHidden=T|Text=SMD/SMT|Name=Case\/Package
|RECORD=41|OwnerIndex=541|IndexInSheet=22|OwnerPartId=-1|Location.X=1382|Location.Y=638|Color=8388608|FontID=1|IsHidden=T|Text=90degC|Name=Max Operating Temperature
|RECORD=41|OwnerIndex=541|IndexInSheet=23|OwnerPartId=-1|Location.X=1382|Location.Y=638|Color=8388608|FontID=1|IsHidden=T|Text=50Ohm|Name=Impedance
|RECORD=41|OwnerIndex=541|IndexInSheet=24|OwnerPartId=-1|Location.X=1382|Location.Y=638|Color=8388608|FontID=3|IsHidden=T|Text=http://www.te.com/commerce/DocumentDelivery/DDEController?Action=srchrtrv&DocNm=1909763&DocType=Customer+Drawing&DocLang=English|Name=Datasheet URL
|RECORD=41|OwnerIndex=541|IndexInSheet=25|OwnerPartId=-1|Location.X=1382|Location.Y=638|Color=8388608|FontID=1|IsHidden=T|Text=Gold|Name=Contact Plating
|RECORD=41|OwnerIndex=541|IndexInSheet=26|OwnerPartId=-1|Location.X=1382|Location.Y=638|Color=8388608|FontID=1|IsHidden=T|Text=SurfaceMount|Name=Mounting Technology
|RECORD=41|OwnerIndex=541|IndexInSheet=27|OwnerPartId=-1|Location.X=1382|Location.Y=638|Color=8388608|FontID=1|IsHidden=T|Text=6GHz|Name=Max Frequency
|RECORD=41|OwnerIndex=541|IndexInSheet=28|OwnerPartId=-1|Location.X=1382|Location.Y=638|Color=8388608|FontID=1|IsHidden=T|Text=TECO-1909763-1|Name=Package Reference
|RECORD=41|OwnerIndex=541|IndexInSheet=29|OwnerPartId=-1|Location.X=1382|Location.Y=638|Color=8388608|FontID=1|IsHidden=T|Text=Thermoplastic|Name=Insulation Material
|RECORD=41|OwnerIndex=541|IndexInSheet=30|OwnerPartId=-1|Location.X=1382|Location.Y=638|Color=8388608|FontID=1|IsHidden=T|Text=-40degC|Name=Min Operating Temperature
|RECORD=41|OwnerIndex=541|IndexInSheet=31|OwnerPartId=-1|Location.X=1382|Location.Y=638|Color=8388608|FontID=3|IsHidden=T|Text=http://www.te.com/|Name=Manufacturer URL
|RECORD=41|OwnerIndex=541|IndexInSheet=32|OwnerPartId=-1|Location.X=1382|Location.Y=638|Color=8388608|FontID=1|IsHidden=T|Text=Gold|Name=Body Plating
|RECORD=41|OwnerIndex=541|IndexInSheet=33|OwnerPartId=-1|Location.X=1382|Location.Y=638|Color=8388608|FontID=1|IsHidden=T|Text=Polymer|Name=Dielectric Material
|RECORD=41|OwnerIndex=541|IndexInSheet=34|OwnerPartId=-1|Location.X=1382|Location.Y=638|Color=8388608|FontID=1|IsHidden=T|Text=TE Connectivity|Name=Manufacturer
|RECORD=41|OwnerIndex=541|IndexInSheet=35|OwnerPartId=-1|Location.X=1382|Location.Y=638|Color=8388608|FontID=1|IsHidden=T|Text=Compliant|Name=ELV
|RECORD=41|OwnerIndex=541|IndexInSheet=36|OwnerPartId=-1|Location.X=1382|Location.Y=638|Color=8388608|FontID=1|IsHidden=T|Text=Rev. B2, 11/2015|Name=Datasheet Version
|RECORD=41|OwnerIndex=541|IndexInSheet=37|OwnerPartId=-1|Location.X=1382|Location.Y=638|Color=8388608|FontID=1|IsHidden=T|Text=No|Name=Radiation Hardening
|RECORD=41|OwnerIndex=541|IndexInSheet=38|OwnerPartId=-1|Location.X=1382|Location.Y=638|Color=8388608|FontID=1|IsHidden=T|Text=3-Pin Surface Mount Device, Body 2.6 x 2.6 mm|Name=Package Description
|RECORD=41|OwnerIndex=541|IndexInSheet=39|OwnerPartId=-1|Location.X=1382|Location.Y=638|Color=8388608|FontID=1|IsHidden=T|Text=Beige|Name=Housing Colour
|RECORD=34|OwnerIndex=541|IndexInSheet=-1|OwnerPartId=-1|Location.X=1393|Location.Y=638|Color=8388608|FontID=1|Text=J4|Name=Designator|ReadOnlyState=1
|RECORD=41|OwnerIndex=541|IndexInSheet=-1|OwnerPartId=-1|Location.X=1444|Location.Y=597|Color=8388608|FontID=1|Text=1909763-1|Name=Comment
|RECORD=44|OwnerIndex=541
|RECORD=45|OwnerIndex=587|IndexInSheet=-1|Description=SMD, 3-Leads, Body 2.6x2.6mm, Height 1.25mm|UseComponentLibrary=T|ModelName=TECO-1909763-1_V|ModelType=PCBLIB|DatafileCount=1|ModelDatafileEntity0=TECO-1909763-1_V|ModelDatafileKind0=PCBLib|IsCurrent=T|DatalinksLocked=T|DatabaseDatalinksLocked=T
|RECORD=46|OwnerIndex=588
|RECORD=48|OwnerIndex=588
|RECORD=41|OwnerIndex=590|IndexInSheet=-1|OwnerPartId=-1|Color=8388608|FontID=1|Text=2D|Name=Available Preview Images
|RECORD=1|LibReference=CN-S-4F-RF5|ComponentDescription=Coaxial connector, 50 Ohm, -65 to 165 degC, 5-Pin THD, RoHS, Bulk|PartCount=2|DisplayModeCount=1|IndexInSheet=63|OwnerPartId=-1|Location.X=1394|Location.Y=557|CurrentPartId=1|LibraryPath=*|SourceLibraryName=Altium Content Vault|TargetFileName=*|AreaColor=11599871|Color=128|PartIDLocked=T|DesignItemId=CMP-2000-05705-1|AllPinCount=5
|RECORD=2|OwnerIndex=592|OwnerPartId=1|FormalType=1|Electrical=4|PinConglomerate=51|PinLength=10|Location.X=1434|Location.Y=517|Name=5|Designator=5|SwapIDPart=Ž&Ž1|PinPropagationDelay=0.000000E+000
|RECORD=8|OwnerIndex=592|IsNotAccesible=T|IndexInSheet=1|OwnerPartId=1|Location.X=1414|Location.Y=537|Radius=20|SecondaryRadius=20|LineWidth=1|Color=16711680|AreaColor=16777215
|RECORD=8|OwnerIndex=592|IsNotAccesible=T|IndexInSheet=2|OwnerPartId=1|Location.X=1414|Location.Y=537|Radius=4|SecondaryRadius=4|LineWidth=1|Color=16711680|AreaColor=16777215
|RECORD=2|OwnerIndex=592|OwnerPartId=1|FormalType=1|Electrical=4|PinConglomerate=50|PinLength=10|Location.X=1394|Location.Y=537|Name=1|Designator=1|PinPropagationDelay=0.000000E+000
|RECORD=2|OwnerIndex=592|OwnerPartId=1|FormalType=1|Electrical=4|PinConglomerate=51|PinLength=10|Location.X=1404|Location.Y=517|Name=2|Designator=2|PinPropagationDelay=0.000000E+000
|RECORD=2|OwnerIndex=592|OwnerPartId=1|FormalType=1|Electrical=4|PinConglomerate=51|PinLength=10|Location.X=1414|Location.Y=517|Name=3|Designator=3|PinPropagationDelay=0.000000E+000
|RECORD=2|OwnerIndex=592|OwnerPartId=1|FormalType=1|Electrical=4|PinConglomerate=51|PinLength=10|Location.X=1424|Location.Y=517|Name=4|Designator=4|PinPropagationDelay=0.000000E+000
|RECORD=6|OwnerIndex=592|IsNotAccesible=T|IndexInSheet=7|OwnerPartId=1|LineWidth=1|Color=16711680|LocationCount=5|X1=1394|Y1=517|X2=1394|Y2=557|X3=1434|Y3=557|X4=1434|Y4=517|X5=1394|Y5=517
|RECORD=6|OwnerIndex=592|IsNotAccesible=T|IndexInSheet=8|OwnerPartId=1|LineWidth=1|Color=16711680|LocationCount=2|X1=1394|Y1=537|X2=1410|Y2=537
|RECORD=41|OwnerIndex=592|IndexInSheet=9|OwnerPartId=-1|Location.X=1382|Location.Y=558|Color=8388608|FontID=1|IsHidden=T|Text=ThroughHole|Name=Mounting Technology
|RECORD=41|OwnerIndex=592|IndexInSheet=10|OwnerPartId=-1|Location.X=1382|Location.Y=558|Color=8388608|FontID=1|IsHidden=T|Text=ThroughHole,RightAngle|Name=Mounting Type
|RECORD=41|OwnerIndex=592|IndexInSheet=11|OwnerPartId=-1|Location.X=1382|Location.Y=558|Color=8388608|FontID=1|IsHidden=T|Text=-|Name=Cable Group
|RECORD=41|OwnerIndex=592|IndexInSheet=12|OwnerPartId=-1|Location.X=1382|Location.Y=558|Color=8388608|FontID=1|IsHidden=T|Text=901-143-6RFXMountingHole|Name=Catalog Drawings
|RECORD=41|OwnerIndex=592|IndexInSheet=13|OwnerPartId=-1|Location.X=1382|Location.Y=558|Color=8388608|FontID=1|IsHidden=T|Text=901-143-6RFX.igs|Name=3D Model
|RECORD=41|OwnerIndex=592|IndexInSheet=14|OwnerPartId=-1|Location.X=1382|Location.Y=558|Color=8388608|FontID=1|IsHidden=T|Text=-|Name=Series
|RECORD=41|OwnerIndex=592|IndexInSheet=15|OwnerPartId=-1|Location.X=1382|Location.Y=558|Color=8388608|FontID=1|IsHidden=T|Text=5-Pin Through Hole Device, Body 7 x 7 mm, Pitch 2.54 mm|Name=Package Description
|RECORD=41|OwnerIndex=592|IndexInSheet=16|OwnerPartId=-1|Location.X=1382|Location.Y=558|Color=8388608|FontID=1|IsHidden=T|Text=901-143-6RFX|Name=Package Reference
|RECORD=41|OwnerIndex=592|IndexInSheet=17|OwnerPartId=-1|Location.X=1382|Location.Y=558|Color=8388608|FontID=1|IsHidden=T|Text=Brass|Name=Body Material
|RECORD=41|OwnerIndex=592|IndexInSheet=18|OwnerPartId=-1|Location.X=1382|Location.Y=558|Color=8388608|FontID=1|IsHidden=T|Text=-|Name=Voltage Rating
|RECORD=41|OwnerIndex=592|IndexInSheet=19|OwnerPartId=-1|Location.X=1382|Location.Y=558|Color=8388608|FontID=1|IsHidden=T|Text=1|Name=Standard Package
|RECORD=41|OwnerIndex=592|IndexInSheet=20|OwnerPartId=-1|Location.X=1382|Location.Y=558|Color=8388608|FontID=1|IsHidden=T|Text=Jack,FemaleSocket|Name=Connector Type
|RECORD=41|OwnerIndex=592|IndexInSheet=21|OwnerPartId=-1|Location.X=1382|Location.Y=558|Color=8388608|FontID=1|IsHidden=T|Text=Threaded|Name=Fastening Type
|RECORD=41|OwnerIndex=592|IndexInSheet=22|OwnerPartId=-1|Location.X=1382|Location.Y=558|Color=8388608|FontID=1|IsHidden=T|Text=Gold|Name=Housing Color
|RECORD=41|OwnerIndex=592|IndexInSheet=23|OwnerPartId=-1|Location.X=1382|Location.Y=558|Color=8388608|FontID=1|IsHidden=T|Text=Solder|Name=Shield Termination
|RECORD=41|OwnerIndex=592|IndexInSheet=24|OwnerPartId=-1|Location.X=1382|Location.Y=558|Color=8388608|FontID=1|IsHidden=T|Text=901-143-6-RFX9011436RFXARFX1232|Name=Other Names
|RECORD=41|OwnerIndex=592|IndexInSheet=25|OwnerPartId=-1|Location.X=1382|Location.Y=558|Color=8388608|FontID=3|IsHidden=T|Text=http://www.amphenolrf.com/downloads/dl/file/id/2712/product/3102/901_143_6rfx_customer_drawing.pdf|Name=Datasheet URL
|RECORD=41|OwnerIndex=592|IndexInSheet=26|OwnerPartId=-1|Location.X=1382|Location.Y=558|Color=8388608|FontID=1|IsHidden=T|Text=CoaxialConnectors(RF)|Name=Family
|RECORD=41|OwnerIndex=592|IndexInSheet=27|OwnerPartId=-1|Location.X=1382|Location.Y=558|Color=8388608|FontID=1|IsHidden=T|Text=SMA,RFX|Name=Online Catalog
|RECORD=41|OwnerIndex=592|IndexInSheet=28|OwnerPartId=-1|Location.X=1382|Location.Y=558|Color=8388608|FontID=1|IsHidden=T|Text=18GHz|Name=Frequency - Max
|RECORD=41|OwnerIndex=592|IndexInSheet=29|OwnerPartId=-1|Location.X=1382|Location.Y=558|Color=8388608|FontID=1|IsHidden=T|Text=Solder|Name=Contact Termination
|RECORD=41|OwnerIndex=592|IndexInSheet=30|OwnerPartId=-1|Location.X=1382|Location.Y=558|Color=8388608|FontID=3|IsHidden=T|Text=http://www.amphenol.com/|Name=Manufacturer URL
|RECORD=41|OwnerIndex=592|IndexInSheet=31|OwnerPartId=-1|Location.X=1382|Location.Y=558|Color=8388608|FontID=1|IsHidden=T|Text=Amphenol|Name=Manufacturer
|RECORD=41|OwnerIndex=592|IndexInSheet=32|OwnerPartId=-1|Location.X=1382|Location.Y=558|Color=8388608|FontID=1|IsHidden=T|Text=-65°C~165°C|Name=Operating Temperature
|RECORD=41|OwnerIndex=592|IndexInSheet=33|OwnerPartId=-1|Location.X=1382|Location.Y=558|Color=8388608|FontID=1|IsHidden=T|Text=Connectors,Interconnects|Name=Category
|RECORD=41|OwnerIndex=592|IndexInSheet=34|OwnerPartId=-1|Location.X=1382|Location.Y=558|Color=8388608|FontID=1|IsHidden=T|Text=Bulk|Name=Packaging
|RECORD=41|OwnerIndex=592|IndexInSheet=35|OwnerPartId=-1|Location.X=1382|Location.Y=558|Color=8388608|FontID=1|IsHidden=T|Text=Gold|Name=Body Finish
|RECORD=41|OwnerIndex=592|IndexInSheet=36|OwnerPartId=-1|Location.X=1382|Location.Y=558|Color=8388608|FontID=1|IsHidden=T|Text=Polytetrafluoroethylene(PTFE)|Name=Dielectric Material
|RECORD=41|OwnerIndex=592|IndexInSheet=37|OwnerPartId=-1|Location.X=1382|Location.Y=558|Color=8388608|FontID=1|IsHidden=T|Text=BerylliumCopper|Name=Center Contact Material
|RECORD=41|OwnerIndex=592|IndexInSheet=38|OwnerPartId=-1|Location.X=1382|Location.Y=558|Color=8388608|FontID=1|IsHidden=T|Text=50Ohm|Name=Impedance
|RECORD=41|OwnerIndex=592|IndexInSheet=39|OwnerPartId=-1|Location.X=1382|Location.Y=558|Color=8388608|FontID=1|IsHidden=T|Text=-|Name=Features
|RECORD=41|OwnerIndex=592|IndexInSheet=40|OwnerPartId=-1|Location.X=1382|Location.Y=558|Color=8388608|FontID=1|IsHidden=T|Text=SMA|Name=Connector Style
|RECORD=41|OwnerIndex=592|IndexInSheet=41|OwnerPartId=-1|Location.X=1382|Location.Y=558|Color=8388608|FontID=1|IsHidden=T|Text=Gold|Name=Center Contact Plating
|RECORD=41|OwnerIndex=592|IndexInSheet=42|OwnerPartId=-1|Location.X=1382|Location.Y=558|Color=8388608|FontID=1|IsHidden=T|Text=Rev. C, 06/2010|Name=Datasheet Version
|RECORD=41|OwnerIndex=592|IndexInSheet=43|OwnerPartId=-1|Location.X=1382|Location.Y=558|Color=8388608|FontID=1|IsHidden=T|Text=-|Name=Ingress Protection
|RECORD=34|OwnerIndex=592|IndexInSheet=-1|OwnerPartId=-1|Location.X=1393|Location.Y=558|Color=8388608|FontID=1|Text=AN4|Name=Designator|ReadOnlyState=1
|RECORD=41|OwnerIndex=592|IndexInSheet=-1|OwnerPartId=-1|Location.X=1444|Location.Y=507|Color=8388608|FontID=1|Text=RF2-49B-T-00-50-G-HDW|Name=Comment
|RECORD=44|OwnerIndex=592
|RECORD=45|OwnerIndex=644|IndexInSheet=-1|Description=THD, 5-Leads, Body 7x7mm, Pitch 2.54mm|UseComponentLibrary=T|ModelName=AMPH-901-143-6RFX_V|ModelType=PCBLIB|DatafileCount=1|ModelDatafileEntity0=AMPH-901-143-6RFX_V|ModelDatafileKind0=PCBLib|IsCurrent=T|DatalinksLocked=T|DatabaseDatalinksLocked=T
|RECORD=46|OwnerIndex=645
|RECORD=48|OwnerIndex=645
|RECORD=41|OwnerIndex=647|IndexInSheet=-1|OwnerPartId=-1|Color=8388608|FontID=1|Text=2D|Name=Available Preview Images
|RECORD=17|IndexInSheet=64|OwnerPartId=-1|Style=4|ShowNetName=T|Location.X=1464|Location.Y=577|Orientation=3|Color=128|FontID=1|Text=GND
|RECORD=1|LibReference=RES-2|ComponentDescription=General Purpose Chip Resistor, 49.9 Ohm, +/- 1%, -55 to 155 degC, 0603 (1608 Metric), RoHS, Tape and Reel|PartCount=2|DisplayModeCount=1|IndexInSheet=65|OwnerPartId=-1|Location.X=1299|Location.Y=617|CurrentPartId=1|LibraryPath=*|SourceLibraryName=Altium Content Vault|TargetFileName=*|AreaColor=11599871|Color=128|PartIDLocked=T|DesignItemId=CMP-1659-00036-1|AllPinCount=2
|RECORD=2|OwnerIndex=650|OwnerPartId=1|FormalType=1|Electrical=4|PinConglomerate=32|PinLength=10|Location.X=1319|Location.Y=617|Name=2|Designator=2|PinPropagationDelay=0.000000E+000
|RECORD=2|OwnerIndex=650|OwnerPartId=1|FormalType=1|Electrical=4|PinConglomerate=34|PinLength=10|Location.X=1299|Location.Y=617|Name=1|Designator=1|PinPropagationDelay=0.000000E+000
|RECORD=6|OwnerIndex=650|IsNotAccesible=T|IndexInSheet=2|OwnerPartId=1|LineWidth=1|Color=16711680|LocationCount=10|X1=1319|Y1=617|X2=1315|Y2=617|X3=1314|Y3=615|X4=1312|Y4=619|X5=1310|Y5=615|X6=1308|Y6=619|X7=1306|Y7=615|X8=1304|Y8=619|X9=1303|Y9=617|X10=1299|Y10=617
|RECORD=41|OwnerIndex=650|IndexInSheet=3|OwnerPartId=-1|Location.X=1287|Location.Y=632|Color=8388608|FontID=1|IsHidden=T|Text=0603|Name=PackageReference
|RECORD=41|OwnerIndex=650|IndexInSheet=4|OwnerPartId=-1|Location.X=1287|Location.Y=632|Color=8388608|FontID=1|IsHidden=T|Text=Tray|Name=Packaging
|RECORD=41|OwnerIndex=650|IndexInSheet=5|OwnerPartId=-1|Location.X=1287|Location.Y=632|Color=8388608|FontID=1|IsHidden=T|Text=Datasheet|Name=ComponentLink2Description
|RECORD=41|OwnerIndex=650|IndexInSheet=6|OwnerPartId=-1|Location.X=1287|Location.Y=632|Color=8388608|FontID=1|IsHidden=T|Text=Manufacturer URL|Name=ComponentLink1Description
|RECORD=41|OwnerIndex=650|IndexInSheet=7|OwnerPartId=-1|Location.X=1287|Location.Y=632|Color=8388608|FontID=3|IsHidden=T|Text=https://datasheet.ciiva.com/11808/0900766b80f96399-11808223.pdf|Name=ComponentLink2URL
|RECORD=41|OwnerIndex=650|IndexInSheet=8|OwnerPartId=-1|Location.X=1287|Location.Y=632|Color=8388608|FontID=1|IsHidden=T|Text=true|Name=RoHSCompliant
|RECORD=41|OwnerIndex=650|IndexInSheet=9|OwnerPartId=-1|Location.X=1287|Location.Y=632|Color=8388608|FontID=1|IsHidden=T|Text=85 degC|Name=Max Operating Temperature
|RECORD=41|OwnerIndex=650|IndexInSheet=10|OwnerPartId=-1|Location.X=1287|Location.Y=632|Color=8388608|FontID=1|IsHidden=T|Text=3.63 V|Name=Max Supply Voltage
|RECORD=41|OwnerIndex=650|IndexInSheet=11|OwnerPartId=-1|Location.X=1287|Location.Y=632|Color=8388608|FontID=3|IsHidden=T|Text=http://www.yageo.com/|Name=ComponentLink1URL
|RECORD=41|OwnerIndex=650|IndexInSheet=12|OwnerPartId=-1|Location.X=1287|Location.Y=632|Color=8388608|FontID=1|IsHidden=T|Text=2-Pin Surface Mount Device, Body 1.6 x 0.8 mm|Name=PackageDescription
|RECORD=41|OwnerIndex=650|IndexInSheet=13|OwnerPartId=-1|Location.X=1287|Location.Y=632|Color=8388608|FontID=1|IsHidden=T|Text=LQFP|Name=Case\Package
|RECORD=41|OwnerIndex=650|IndexInSheet=14|OwnerPartId=-1|Location.X=1287|Location.Y=632|Color=8388608|FontID=1|IsHidden=T|Text=Rev. 4, 04/2009|Name=DatasheetVersion
|RECORD=41|OwnerIndex=650|IndexInSheet=15|OwnerPartId=-1|Location.X=1287|Location.Y=632|Color=8388608|FontID=1|IsHidden=T|Text=-40 degC|Name=Min Operating Temperature
|RECORD=41|OwnerIndex=650|IndexInSheet=16|OwnerPartId=-1|Location.X=1287|Location.Y=632|Color=8388608|FontID=1|IsHidden=T|Text=SPI|Name=Interface
|RECORD=41|OwnerIndex=650|IndexInSheet=17|OwnerPartId=-1|Location.X=1287|Location.Y=632|Color=8388608|FontID=1|IsHidden=T|Text=250|Name=Package Quantity
|RECORD=41|OwnerIndex=650|IndexInSheet=18|OwnerPartId=-1|Location.X=1287|Location.Y=632|Color=8388608|FontID=1|IsHidden=T|Text=2.97 V|Name=Min Supply Voltage
|RECORD=41|OwnerIndex=650|IndexInSheet=19|OwnerPartId=-1|Location.X=1287|Location.Y=632|Color=8388608|FontID=1|IsHidden=T|Text=48|Name=Pins
|RECORD=34|OwnerIndex=650|IndexInSheet=-1|OwnerPartId=-1|Location.X=1298|Location.Y=620|Color=8388608|FontID=1|Text=R34|Name=Designator|ReadOnlyState=1
|RECORD=41|OwnerIndex=650|IndexInSheet=-1|OwnerPartId=-1|Location.X=1298|Location.Y=604|Color=8388608|FontID=1|Text=49.9R|Name=Comment
|RECORD=44|OwnerIndex=650
|RECORD=45|OwnerIndex=675|IndexInSheet=-1|Description=Chip Resistor, 2-Leads, Body 1.70x0.90mm, IPC Medium Density|UseComponentLibrary=T|ModelName=RESC1608X55X25NL10T15|ModelType=PCBLIB|DatafileCount=1|ModelDatafileEntity0=RESC1608X55X25NL10T15|ModelDatafileKind0=PCBLib|IsCurrent=T|DatalinksLocked=T|DatabaseDatalinksLocked=T
|RECORD=46|OwnerIndex=676
|RECORD=48|OwnerIndex=676
|RECORD=41|OwnerIndex=678|IndexInSheet=-1|OwnerPartId=-1|Color=8388608|FontID=1|IsHidden=T|Text=2D|Name=Available Preview Images
|RECORD=45|OwnerIndex=675|IndexInSheet=-1|Description=Chip Resistor, 2-Leads, Body 1.70x0.90mm, IPC Low Density|UseComponentLibrary=T|ModelName=RESC1608X55X25ML10T15|ModelType=PCBLIB|DatafileCount=1|ModelDatafileEntity0=RESC1608X55X25ML10T15|ModelDatafileKind0=PCBLib|DatalinksLocked=T|DatabaseDatalinksLocked=T
|RECORD=46|OwnerIndex=680
|RECORD=48|OwnerIndex=680
|RECORD=41|OwnerIndex=682|IndexInSheet=-1|OwnerPartId=-1|Color=8388608|FontID=1|IsHidden=T|Text=2D|Name=Available Preview Images
|RECORD=45|OwnerIndex=675|IndexInSheet=-1|Description=Chip Resistor, 2-Leads, Body 1.70x0.90mm, IPC High Density|UseComponentLibrary=T|ModelName=RESC1608X55X25LL10T15|ModelType=PCBLIB|DatafileCount=1|ModelDatafileEntity0=RESC1608X55X25LL10T15|ModelDatafileKind0=PCBLib|DatalinksLocked=T|DatabaseDatalinksLocked=T
|RECORD=46|OwnerIndex=684
|RECORD=48|OwnerIndex=684
|RECORD=41|OwnerIndex=686|IndexInSheet=-1|OwnerPartId=-1|Color=8388608|FontID=1|IsHidden=T|Text=2D|Name=Available Preview Images
|RECORD=17|IndexInSheet=66|OwnerPartId=-1|ShowNetName=T|Location.X=1024|Location.Y=617|Orientation=2|Color=255|FontID=1|Text=ANT4_OUT|IsCrossSheetConnector=T
|RECORD=17|IndexInSheet=67|OwnerPartId=-1|ShowNetName=T|Location.X=1030|Location.Y=720|Orientation=1|Color=128|FontID=1|Text=+3.3V
|RECORD=17|IndexInSheet=68|OwnerPartId=-1|ShowNetName=T|Location.X=1060|Location.Y=720|Orientation=1|Color=128|FontID=1|Text=+3.3V
|RECORD=17|IndexInSheet=69|OwnerPartId=-1|ShowNetName=T|Location.X=1024|Location.Y=562|Orientation=2|Color=255|FontID=1|Text=ANT4_IN|IsCrossSheetConnector=T
|RECORD=17|IndexInSheet=70|OwnerPartId=-1|Style=4|ShowNetName=T|Location.X=1144|Location.Y=487|Orientation=3|Color=128|FontID=1|Text=GND
|RECORD=17|IndexInSheet=71|OwnerPartId=-1|Style=4|ShowNetName=T|Location.X=1094|Location.Y=487|Orientation=3|Color=128|FontID=1|Text=GND
|RECORD=17|IndexInSheet=72|OwnerPartId=-1|ShowNetName=T|Location.X=1094|Location.Y=707|Orientation=1|Color=128|FontID=1|Text=+3.3V
|RECORD=1|LibReference=NC7WV125K8X|ComponentDescription=Integrated Circuit|PartCount=2|DisplayModeCount=1|IndexInSheet=73|OwnerPartId=-1|Location.X=394|Location.Y=552|CurrentPartId=1|LibraryPath=*|SourceLibraryName=SamacSys.SchLib|TargetFileName=*|AreaColor=11599871|Color=128|PartIDLocked=T|DesignItemId=NC7WV125K8X|AllPinCount=8
|RECORD=41|OwnerIndex=695|OwnerPartId=-1|Location.X=394|Location.Y=552|Color=8388608|FontID=3|IsHidden=T|Text=https://www.mouser.com/datasheet/2/308/NC7WV125-1301459.pdf|Name=Datasheet Link
|RECORD=41|OwnerIndex=695|IndexInSheet=1|OwnerPartId=-1|Location.X=394|Location.Y=552|Color=8388608|FontID=1|IsHidden=T|Text=0.9mm|Name=Height
|RECORD=41|OwnerIndex=695|IndexInSheet=2|OwnerPartId=-1|Location.X=394|Location.Y=552|Color=8388608|FontID=1|IsHidden=T|Text=ON Semiconductor|Name=Manufacturer_Name
|RECORD=41|OwnerIndex=695|IndexInSheet=3|OwnerPartId=-1|Location.X=394|Location.Y=552|Color=8388608|FontID=1|IsHidden=T|Text=NC7WV125K8X|Name=Manufacturer_Part_Number
|RECORD=41|OwnerIndex=695|IndexInSheet=4|OwnerPartId=-1|Location.X=394|Location.Y=552|Color=8388608|FontID=1|IsHidden=T|Text=512-NC7WV125K8X|Name=Mouser Part Number
|RECORD=41|OwnerIndex=695|IndexInSheet=5|OwnerPartId=-1|Location.X=394|Location.Y=552|Color=8388608|FontID=3|IsHidden=T|Text=https://www.mouser.com/Search/Refine.aspx?Keyword=512-NC7WV125K8X|Name=Mouser Price/Stock
|RECORD=41|OwnerIndex=695|IndexInSheet=6|OwnerPartId=-1|Location.X=394|Location.Y=552|Color=8388608|FontID=1|IsHidden=T|Text=NC7WV125K8X|Name=Arrow Part Number
|RECORD=41|OwnerIndex=695|IndexInSheet=7|OwnerPartId=-1|Location.X=394|Location.Y=552|Color=8388608|FontID=3|IsHidden=T|Text=https://www.arrow.com/en/products/nc7wv125k8x/on-semiconductor|Name=Arrow Price/Stock
|RECORD=14|OwnerIndex=695|IsNotAccesible=T|IndexInSheet=8|OwnerPartId=1|Location.X=414|Location.Y=527|Corner.X=484|Corner.Y=652|LineWidth=1|Color=128|AreaColor=11599871|IsSolid=T
|RECORD=2|OwnerIndex=695|OwnerPartId=1|FormalType=1|Electrical=4|PinConglomerate=58|PinLength=20|Location.X=414|Location.Y=642|Designator=1|SwapIDPart=Ž&Ž||PinPropagationDelay=0.000000E+000
|RECORD=2|OwnerIndex=695|OwnerPartId=1|FormalType=1|Electrical=4|PinConglomerate=58|PinLength=20|Location.X=414|Location.Y=617|Designator=2|SwapIDPart=Ž&Ž||PinPropagationDelay=0.000000E+000
|RECORD=2|OwnerIndex=695|OwnerPartId=1|FormalType=1|Electrical=4|PinConglomerate=58|PinLength=20|Location.X=414|Location.Y=562|Designator=3|SwapIDPart=Ž&Ž||PinPropagationDelay=0.000000E+000
|RECORD=2|OwnerIndex=695|OwnerPartId=1|FormalType=1|Electrical=4|PinConglomerate=58|PinLength=20|Location.X=414|Location.Y=532|Name=GND|Designator=4|SwapIDPart=Ž&Ž||PinPropagationDelay=0.000000E+000
|RECORD=2|OwnerIndex=695|OwnerPartId=1|FormalType=1|Electrical=4|PinConglomerate=58|PinLength=20|Location.X=414|Location.Y=542|Name=VCC|Designator=8|SwapIDPart=Ž&Ž||PinPropagationDelay=0.000000E+000
|RECORD=2|OwnerIndex=695|OwnerPartId=1|FormalType=1|Electrical=4|PinConglomerate=58|PinLength=20|Location.X=414|Location.Y=587|Designator=7|SwapIDPart=Ž&Ž||PinPropagationDelay=0.000000E+000
|RECORD=2|OwnerIndex=695|OwnerPartId=1|FormalType=1|Electrical=4|PinConglomerate=56|PinLength=20|Location.X=484|Location.Y=617|Designator=6|SwapIDPart=Ž&Ž||PinPropagationDelay=0.000000E+000
|RECORD=2|OwnerIndex=695|OwnerPartId=1|FormalType=1|Electrical=4|PinConglomerate=56|PinLength=20|Location.X=484|Location.Y=562|Designator=5|SwapIDPart=Ž&Ž||PinPropagationDelay=0.000000E+000
|RECORD=6|OwnerIndex=695|IsNotAccesible=T|IndexInSheet=17|OwnerPartId=1|LineWidth=1|Color=16711680|LocationCount=4|X1=439|Y1=627|X2=439|Y2=607|X3=459|Y3=617|X4=439|Y4=627
|RECORD=12|OwnerIndex=695|IsNotAccesible=T|IndexInSheet=18|OwnerPartId=1|Location.X=449|Location.Y=624|Radius=1|Radius_Frac=79777|LineWidth=1|EndAngle=360.000|Color=16711680
|RECORD=6|OwnerIndex=695|IsNotAccesible=T|IndexInSheet=19|OwnerPartId=1|LineWidth=1|Color=16711680|LocationCount=4|X1=459|Y1=572|X2=459|Y2=552|X3=439|Y3=562|X4=459|Y4=572
|RECORD=12|OwnerIndex=695|IsNotAccesible=T|IndexInSheet=20|OwnerPartId=1|Location.X=449|Location.Y=569|Radius=1|Radius_Frac=79777|LineWidth=1|EndAngle=360.000|Color=16711680
|RECORD=6|OwnerIndex=695|IsNotAccesible=T|IndexInSheet=21|OwnerPartId=1|LineWidth=1|Color=16711680|LocationCount=3|X1=449|Y1=571|X2=449|Y2=587|X3=414|Y3=587
|RECORD=6|OwnerIndex=695|IsNotAccesible=T|IndexInSheet=22|OwnerPartId=1|LineWidth=1|Color=16711680|LocationCount=3|X1=449|Y1=626|X2=449|Y2=642|X3=414|Y3=642
|RECORD=6|OwnerIndex=695|IsNotAccesible=T|IndexInSheet=23|OwnerPartId=1|LineWidth=1|Color=16711680|LocationCount=2|X1=414|Y1=617|X2=439|Y2=617
|RECORD=6|OwnerIndex=695|IsNotAccesible=T|IndexInSheet=24|OwnerPartId=1|LineWidth=1|Color=16711680|LocationCount=2|X1=459|Y1=617|X2=484|Y2=617
|RECORD=6|OwnerIndex=695|IsNotAccesible=T|IndexInSheet=25|OwnerPartId=1|LineWidth=1|Color=16711680|LocationCount=2|X1=459|Y1=562|X2=484|Y2=562
|RECORD=6|OwnerIndex=695|IsNotAccesible=T|IndexInSheet=26|OwnerPartId=1|LineWidth=1|Color=16711680|LocationCount=2|X1=439|Y1=562|X2=414|Y2=562
|RECORD=34|OwnerIndex=695|IndexInSheet=-1|OwnerPartId=-1|Location.X=413|Location.Y=652|Color=8388608|FontID=1|Text=U12|Name=Designator|ReadOnlyState=1
|RECORD=41|OwnerIndex=695|IndexInSheet=-1|OwnerPartId=-1|Location.X=413|Location.Y=517|Color=8388608|FontID=1|Text=NC7WV125K8X|Name=Comment
|RECORD=44|OwnerIndex=695
|RECORD=45|OwnerIndex=733|IndexInSheet=-1|ModelName=SOP50P310X90-8N|ModelType=PCBLIB|DatafileCount=1|ModelDatafile0=C:\Users\<user>\Documents\AltiumLL\SamacSys.PcbLib|ModelDatafileEntity0=SOP50P310X90-8N|ModelDatafileKind0=PCBLIB|IsCurrent=T
|RECORD=46|OwnerIndex=734
|RECORD=48|OwnerIndex=734
|RECORD=17|IndexInSheet=74|OwnerPartId=-1|Style=4|ShowNetName=T|Location.X=704|Location.Y=487|Orientation=3|Color=128|FontID=1|Text=GND
|RECORD=1|LibReference=CN-1P-M-RF3|ComponentDescription=Ultra Miniature Coaxial Connector Jack, 60 V, 50 Ohm, -40 to 90 degC, RoHS, Tape and Reel|PartCount=2|DisplayModeCount=1|IndexInSheet=75|OwnerPartId=-1|Location.X=634|Location.Y=637|CurrentPartId=1|LibraryPath=*|SourceLibraryName=Altium Content Vault|TargetFileName=*|AreaColor=11599871|Color=128|PartIDLocked=T|DesignItemId=CMP-2000-07505-1|AllPinCount=3
|RECORD=8|OwnerIndex=738|IsNotAccesible=T|OwnerPartId=1|Location.X=654|Location.Y=617|Radius=20|SecondaryRadius=20|LineWidth=1|Color=16711680|AreaColor=16777215
|RECORD=8|OwnerIndex=738|IsNotAccesible=T|IndexInSheet=1|OwnerPartId=1|Location.X=654|Location.Y=617|Radius=4|SecondaryRadius=4|LineWidth=1|Color=16711680|AreaColor=16777215
|RECORD=2|OwnerIndex=738|OwnerPartId=1|FormalType=1|Electrical=4|PinConglomerate=51|PinLength=10|Location.X=644|Location.Y=597|Name=1|Designator=1|PinPropagationDelay=0.000000E+000
|RECORD=2|OwnerIndex=738|OwnerPartId=1|FormalType=1|Electrical=4|PinConglomerate=50|PinLength=10|Location.X=634|Location.Y=617|Name=2|Designator=2|PinPropagationDelay=0.000000E+000
|RECORD=2|OwnerIndex=738|OwnerPartId=1|FormalType=1|Electrical=4|PinConglomerate=51|PinLength=10|Location.X=664|Location.Y=597|Name=3|Designator=3|PinPropagationDelay=0.000000E+000
|RECORD=6|OwnerIndex=738|IsNotAccesible=T|IndexInSheet=5|OwnerPartId=1|LineWidth=1|Color=16711680|LocationCount=5|X1=634|Y1=597|X2=634|Y2=637|X3=674|Y3=637|X4=674|Y4=597|X5=634|Y5=597
|RECORD=6|OwnerIndex=738|IsNotAccesible=T|IndexInSheet=6|OwnerPartId=1|LineWidth=1|Color=16711680|LocationCount=2|X1=634|Y1=617|X2=650|Y2=617
|RECORD=41|OwnerIndex=738|IndexInSheet=7|OwnerPartId=-1|Location.X=622|Location.Y=638|Color=8388608|FontID=1|IsHidden=T|Text=Straight|Name=Orientation
|RECORD=41|OwnerIndex=738|IndexInSheet=8|OwnerPartId=-1|Location.X=622|Location.Y=638|Color=8388608|FontID=1|IsHidden=T|Text=Female|Name=Gender
|RECORD=41|OwnerIndex=738|IndexInSheet=9|OwnerPartId=-1|Location.X=622|Location.Y=638|Color=8388608|FontID=1|IsHidden=T|Text=Vertical|Name=PCB Mounting Orientation
|RECORD=41|OwnerIndex=738|IndexInSheet=10|OwnerPartId=-1|Location.X=622|Location.Y=638|Color=8388608|FontID=1|IsHidden=T|Text=SurfaceMount|Name=Mount
|RECORD=41|OwnerIndex=738|IndexInSheet=11|OwnerPartId=-1|Location.X=622|Location.Y=638|Color=8388608|FontID=1|IsHidden=T|Text=3mm|Name=Length
|RECORD=41|OwnerIndex=738|IndexInSheet=12|OwnerPartId=-1|Location.X=622|Location.Y=638|Color=8388608|FontID=1|IsHidden=T|Text=TapeandReel|Name=Packaging
|RECORD=41|OwnerIndex=738|IndexInSheet=13|OwnerPartId=-1|Location.X=622|Location.Y=638|Color=8388608|FontID=1|IsHidden=T|Text=Jack|Name=Connector Type
|RECORD=41|OwnerIndex=738|IndexInSheet=14|OwnerPartId=-1|Location.X=622|Location.Y=638|Color=8388608|FontID=1|IsHidden=T|Text=LeadFree|Name=Lead Free
|RECORD=41|OwnerIndex=738|IndexInSheet=15|OwnerPartId=-1|Location.X=622|Location.Y=638|Color=8388608|FontID=1|IsHidden=T|Text=1|Name=Package Quantity
|RECORD=41|OwnerIndex=738|IndexInSheet=16|OwnerPartId=-1|Location.X=622|Location.Y=638|Color=8388608|FontID=1|IsHidden=T|Text=SMD/SMT|Name=Termination
|RECORD=41|OwnerIndex=738|IndexInSheet=17|OwnerPartId=-1|Location.X=622|Location.Y=638|Color=8388608|FontID=1|IsHidden=T|Text=CopperAlloy|Name=Contact Material
|RECORD=41|OwnerIndex=738|IndexInSheet=18|OwnerPartId=-1|Location.X=622|Location.Y=638|Color=8388608|FontID=1|IsHidden=T|Text=Pull|Name=Fastening Type
|RECORD=41|OwnerIndex=738|IndexInSheet=19|OwnerPartId=-1|Location.X=622|Location.Y=638|Color=8388608|FontID=1|IsHidden=T|Text=true|Name=RoHSCompliant
|RECORD=41|OwnerIndex=738|IndexInSheet=20|OwnerPartId=-1|Location.X=622|Location.Y=638|Color=8388608|FontID=1|IsHidden=T|Text=LiquidCrystalPolymer|Name=Body Material
|RECORD=41|OwnerIndex=738|IndexInSheet=21|OwnerPartId=-1|Location.X=622|Location.Y=638|Color=8388608|FontID=1|IsHidden=T|Text=SMD/SMT|Name=Case\/Package
|RECORD=41|OwnerIndex=738|IndexInSheet=22|OwnerPartId=-1|Location.X=622|Location.Y=638|Color=8388608|FontID=1|IsHidden=T|Text=90degC|Name=Max Operating Temperature
|RECORD=41|OwnerIndex=738|IndexInSheet=23|OwnerPartId=-1|Location.X=622|Location.Y=638|Color=8388608|FontID=1|IsHidden=T|Text=50Ohm|Name=Impedance
|RECORD=41|OwnerIndex=738|IndexInSheet=24|OwnerPartId=-1|Location.X=622|Location.Y=638|Color=8388608|FontID=3|IsHidden=T|Text=http://www.te.com/commerce/DocumentDelivery/DDEController?Action=srchrtrv&DocNm=1909763&DocType=Customer+Drawing&DocLang=English|Name=Datasheet URL
|RECORD=41|OwnerIndex=738|IndexInSheet=25|OwnerPartId=-1|Location.X=622|Location.Y=638|Color=8388608|FontID=1|IsHidden=T|Text=Gold|Name=Contact Plating
|RECORD=41|OwnerIndex=738|IndexInSheet=26|OwnerPartId=-1|Location.X=622|Location.Y=638|Color=8388608|FontID=1|IsHidden=T|Text=SurfaceMount|Name=Mounting Technology
|RECORD=41|OwnerIndex=738|IndexInSheet=27|OwnerPartId=-1|Location.X=622|Location.Y=638|Color=8388608|FontID=1|IsHidden=T|Text=6GHz|Name=Max Frequency
|RECORD=41|OwnerIndex=738|IndexInSheet=28|OwnerPartId=-1|Location.X=622|Location.Y=638|Color=8388608|FontID=1|IsHidden=T|Text=TECO-1909763-1|Name=Package Reference
|RECORD=41|OwnerIndex=738|IndexInSheet=29|OwnerPartId=-1|Location.X=622|Location.Y=638|Color=8388608|FontID=1|IsHidden=T|Text=Thermoplastic|Name=Insulation Material
|RECORD=41|OwnerIndex=738|IndexInSheet=30|OwnerPartId=-1|Location.X=622|Location.Y=638|Color=8388608|FontID=1|IsHidden=T|Text=-40degC|Name=Min Operating Temperature
|RECORD=41|OwnerIndex=738|IndexInSheet=31|OwnerPartId=-1|Location.X=622|Location.Y=638|Color=8388608|FontID=3|IsHidden=T|Text=http://www.te.com/|Name=Manufacturer URL
|RECORD=41|OwnerIndex=738|IndexInSheet=32|OwnerPartId=-1|Location.X=622|Location.Y=638|Color=8388608|FontID=1|IsHidden=T|Text=Gold|Name=Body Plating
|RECORD=41|OwnerIndex=738|IndexInSheet=33|OwnerPartId=-1|Location.X=622|Location.Y=638|Color=8388608|FontID=1|IsHidden=T|Text=Polymer|Name=Dielectric Material
|RECORD=41|OwnerIndex=738|IndexInSheet=34|OwnerPartId=-1|Location.X=622|Location.Y=638|Color=8388608|FontID=1|IsHidden=T|Text=TE Connectivity|Name=Manufacturer
|RECORD=41|OwnerIndex=738|IndexInSheet=35|OwnerPartId=-1|Location.X=622|Location.Y=638|Color=8388608|FontID=1|IsHidden=T|Text=Compliant|Name=ELV
|RECORD=41|OwnerIndex=738|IndexInSheet=36|OwnerPartId=-1|Location.X=622|Location.Y=638|Color=8388608|FontID=1|IsHidden=T|Text=Rev. B2, 11/2015|Name=Datasheet Version
|RECORD=41|OwnerIndex=738|IndexInSheet=37|OwnerPartId=-1|Location.X=622|Location.Y=638|Color=8388608|FontID=1|IsHidden=T|Text=No|Name=Radiation Hardening
|RECORD=41|OwnerIndex=738|IndexInSheet=38|OwnerPartId=-1|Location.X=622|Location.Y=638|Color=8388608|FontID=1|IsHidden=T|Text=3-Pin Surface Mount Device, Body 2.6 x 2.6 mm|Name=Package Description
|RECORD=41|OwnerIndex=738|IndexInSheet=39|OwnerPartId=-1|Location.X=622|Location.Y=638|Color=8388608|FontID=1|IsHidden=T|Text=Beige|Name=Housing Colour
|RECORD=34|OwnerIndex=738|IndexInSheet=-1|OwnerPartId=-1|Location.X=633|Location.Y=638|Color=8388608|FontID=1|Text=J2|Name=Designator|ReadOnlyState=1
|RECORD=41|OwnerIndex=738|IndexInSheet=-1|OwnerPartId=-1|Location.X=684|Location.Y=597|Color=8388608|FontID=1|Text=1909763-1|Name=Comment
|RECORD=44|OwnerIndex=738
|RECORD=45|OwnerIndex=784|IndexInSheet=-1|Description=SMD, 3-Leads, Body 2.6x2.6mm, Height 1.25mm|UseComponentLibrary=T|ModelName=TECO-1909763-1_V|ModelType=PCBLIB|DatafileCount=1|ModelDatafileEntity0=TECO-1909763-1_V|ModelDatafileKind0=PCBLib|IsCurrent=T|DatalinksLocked=T|DatabaseDatalinksLocked=T
|RECORD=46|OwnerIndex=785
|RECORD=48|OwnerIndex=785
|RECORD=41|OwnerIndex=787|IndexInSheet=-1|OwnerPartId=-1|Color=8388608|FontID=1|Text=2D|Name=Available Preview Images
|RECORD=1|LibReference=CN-S-4F-RF5|ComponentDescription=Coaxial connector, 50 Ohm, -65 to 165 degC, 5-Pin THD, RoHS, Bulk|PartCount=2|DisplayModeCount=1|IndexInSheet=76|OwnerPartId=-1|Location.X=634|Location.Y=557|CurrentPartId=1|LibraryPath=*|SourceLibraryName=Altium Content Vault|TargetFileName=*|AreaColor=11599871|Color=128|PartIDLocked=T|DesignItemId=CMP-2000-05705-1|AllPinCount=5
|RECORD=2|OwnerIndex=789|OwnerPartId=1|FormalType=1|Electrical=4|PinConglomerate=51|PinLength=10|Location.X=674|Location.Y=517|Name=5|Designator=5|SwapIDPart=Ž&Ž1|PinPropagationDelay=0.000000E+000
|RECORD=8|OwnerIndex=789|IsNotAccesible=T|IndexInSheet=1|OwnerPartId=1|Location.X=654|Location.Y=537|Radius=20|SecondaryRadius=20|LineWidth=1|Color=16711680|AreaColor=16777215
|RECORD=8|OwnerIndex=789|IsNotAccesible=T|IndexInSheet=2|OwnerPartId=1|Location.X=654|Location.Y=537|Radius=4|SecondaryRadius=4|LineWidth=1|Color=16711680|AreaColor=16777215
|RECORD=2|OwnerIndex=789|OwnerPartId=1|FormalType=1|Electrical=4|PinConglomerate=50|PinLength=10|Location.X=634|Location.Y=537|Name=1|Designator=1|PinPropagationDelay=0.000000E+000
|RECORD=2|OwnerIndex=789|OwnerPartId=1|FormalType=1|Electrical=4|PinConglomerate=51|PinLength=10|Location.X=644|Location.Y=517|Name=2|Designator=2|PinPropagationDelay=0.000000E+000
|RECORD=2|OwnerIndex=789|OwnerPartId=1|FormalType=1|Electrical=4|PinConglomerate=51|PinLength=10|Location.X=654|Location.Y=517|Name=3|Designator=3|PinPropagationDelay=0.000000E+000
|RECORD=2|OwnerIndex=789|OwnerPartId=1|FormalType=1|Electrical=4|PinConglomerate=51|PinLength=10|Location.X=664|Location.Y=517|Name=4|Designator=4|PinPropagationDelay=0.000000E+000
|RECORD=6|OwnerIndex=789|IsNotAccesible=T|IndexInSheet=7|OwnerPartId=1|LineWidth=1|Color=16711680|LocationCount=5|X1=634|Y1=517|X2=634|Y2=557|X3=674|Y3=557|X4=674|Y4=517|X5=634|Y5=517
|RECORD=6|OwnerIndex=789|IsNotAccesible=T|IndexInSheet=8|OwnerPartId=1|LineWidth=1|Color=16711680|LocationCount=2|X1=634|Y1=537|X2=650|Y2=537
|RECORD=41|OwnerIndex=789|IndexInSheet=9|OwnerPartId=-1|Location.X=622|Location.Y=558|Color=8388608|FontID=1|IsHidden=T|Text=ThroughHole|Name=Mounting Technology
|RECORD=41|OwnerIndex=789|IndexInSheet=10|OwnerPartId=-1|Location.X=622|Location.Y=558|Color=8388608|FontID=1|IsHidden=T|Text=ThroughHole,RightAngle|Name=Mounting Type
|RECORD=41|OwnerIndex=789|IndexInSheet=11|OwnerPartId=-1|Location.X=622|Location.Y=558|Color=8388608|FontID=1|IsHidden=T|Text=-|Name=Cable Group
|RECORD=41|OwnerIndex=789|IndexInSheet=12|OwnerPartId=-1|Location.X=622|Location.Y=558|Color=8388608|FontID=1|IsHidden=T|Text=901-143-6RFXMountingHole|Name=Catalog Drawings
|RECORD=41|OwnerIndex=789|IndexInSheet=13|OwnerPartId=-1|Location.X=622|Location.Y=558|Color=8388608|FontID=1|IsHidden=T|Text=901-143-6RFX.igs|Name=3D Model
|RECORD=41|OwnerIndex=789|IndexInSheet=14|OwnerPartId=-1|Location.X=622|Location.Y=558|Color=8388608|FontID=1|IsHidden=T|Text=-|Name=Series
|RECORD=41|OwnerIndex=789|IndexInSheet=15|OwnerPartId=-1|Location.X=622|Location.Y=558|Color=8388608|FontID=1|IsHidden=T|Text=5-Pin Through Hole Device, Body 7 x 7 mm, Pitch 2.54 mm|Name=Package Description
|RECORD=41|OwnerIndex=789|IndexInSheet=16|OwnerPartId=-1|Location.X=622|Location.Y=558|Color=8388608|FontID=1|IsHidden=T|Text=901-143-6RFX|Name=Package Reference
|RECORD=41|OwnerIndex=789|IndexInSheet=17|OwnerPartId=-1|Location.X=622|Location.Y=558|Color=8388608|FontID=1|IsHidden=T|Text=Brass|Name=Body Material
|RECORD=41|OwnerIndex=789|IndexInSheet=18|OwnerPartId=-1|Location.X=622|Location.Y=558|Color=8388608|FontID=1|IsHidden=T|Text=-|Name=Voltage Rating
|RECORD=41|OwnerIndex=789|IndexInSheet=19|OwnerPartId=-1|Location.X=622|Location.Y=558|Color=8388608|FontID=1|IsHidden=T|Text=1|Name=Standard Package
|RECORD=41|OwnerIndex=789|IndexInSheet=20|OwnerPartId=-1|Location.X=622|Location.Y=558|Color=8388608|FontID=1|IsHidden=T|Text=Jack,FemaleSocket|Name=Connector Type
|RECORD=41|OwnerIndex=789|IndexInSheet=21|OwnerPartId=-1|Location.X=622|Location.Y=558|Color=8388608|FontID=1|IsHidden=T|Text=Threaded|Name=Fastening Type
|RECORD=41|OwnerIndex=789|IndexInSheet=22|OwnerPartId=-1|Location.X=622|Location.Y=558|Color=8388608|FontID=1|IsHidden=T|Text=Gold|Name=Housing Color
|RECORD=41|OwnerIndex=789|IndexInSheet=23|OwnerPartId=-1|Location.X=622|Location.Y=558|Color=8388608|FontID=1|IsHidden=T|Text=Solder|Name=Shield Termination
|RECORD=41|OwnerIndex=789|IndexInSheet=24|OwnerPartId=-1|Location.X=622|Location.Y=558|Color=8388608|FontID=1|IsHidden=T|Text=901-143-6-RFX9011436RFXARFX1232|Name=Other Names
|RECORD=41|OwnerIndex=789|IndexInSheet=25|OwnerPartId=-1|Location.X=622|Location.Y=558|Color=8388608|FontID=3|IsHidden=T|Text=http://www.amphenolrf.com/downloads/dl/file/id/2712/product/3102/901_143_6rfx_customer_drawing.pdf|Name=Datasheet URL
|RECORD=41|OwnerIndex=789|IndexInSheet=26|OwnerPartId=-1|Location.X=622|Location.Y=558|Color=8388608|FontID=1|IsHidden=T|Text=CoaxialConnectors(RF)|Name=Family
|RECORD=41|OwnerIndex=789|IndexInSheet=27|OwnerPartId=-1|Location.X=622|Location.Y=558|Color=8388608|FontID=1|IsHidden=T|Text=SMA,RFX|Name=Online Catalog
|RECORD=41|OwnerIndex=789|IndexInSheet=28|OwnerPartId=-1|Location.X=622|Location.Y=558|Color=8388608|FontID=1|IsHidden=T|Text=18GHz|Name=Frequency - Max
|RECORD=41|OwnerIndex=789|IndexInSheet=29|OwnerPartId=-1|Location.X=622|Location.Y=558|Color=8388608|FontID=1|IsHidden=T|Text=Solder|Name=Contact Termination
|RECORD=41|OwnerIndex=789|IndexInSheet=30|OwnerPartId=-1|Location.X=622|Location.Y=558|Color=8388608|FontID=3|IsHidden=T|Text=http://www.amphenol.com/|Name=Manufacturer URL
|RECORD=41|OwnerIndex=789|IndexInSheet=31|OwnerPartId=-1|Location.X=622|Location.Y=558|Color=8388608|FontID=1|IsHidden=T|Text=Amphenol|Name=Manufacturer
|RECORD=41|OwnerIndex=789|IndexInSheet=32|OwnerPartId=-1|Location.X=622|Location.Y=558|Color=8388608|FontID=1|IsHidden=T|Text=-65°C~165°C|Name=Operating Temperature
|RECORD=41|OwnerIndex=789|IndexInSheet=33|OwnerPartId=-1|Location.X=622|Location.Y=558|Color=8388608|FontID=1|IsHidden=T|Text=Connectors,Interconnects|Name=Category
|RECORD=41|OwnerIndex=789|IndexInSheet=34|OwnerPartId=-1|Location.X=622|Location.Y=558|Color=8388608|FontID=1|IsHidden=T|Text=Bulk|Name=Packaging
|RECORD=41|OwnerIndex=789|IndexInSheet=35|OwnerPartId=-1|Location.X=622|Location.Y=558|Color=8388608|FontID=1|IsHidden=T|Text=Gold|Name=Body Finish
|RECORD=41|OwnerIndex=789|IndexInSheet=36|OwnerPartId=-1|Location.X=622|Location.Y=558|Color=8388608|FontID=1|IsHidden=T|Text=Polytetrafluoroethylene(PTFE)|Name=Dielectric Material
|RECORD=41|OwnerIndex=789|IndexInSheet=37|OwnerPartId=-1|Location.X=622|Location.Y=558|Color=8388608|FontID=1|IsHidden=T|Text=BerylliumCopper|Name=Center Contact Material
|RECORD=41|OwnerIndex=789|IndexInSheet=38|OwnerPartId=-1|Location.X=622|Location.Y=558|Color=8388608|FontID=1|IsHidden=T|Text=50Ohm|Name=Impedance
|RECORD=41|OwnerIndex=789|IndexInSheet=39|OwnerPartId=-1|Location.X=622|Location.Y=558|Color=8388608|FontID=1|IsHidden=T|Text=-|Name=Features
|RECORD=41|OwnerIndex=789|IndexInSheet=40|OwnerPartId=-1|Location.X=622|Location.Y=558|Color=8388608|FontID=1|IsHidden=T|Text=SMA|Name=Connector Style
|RECORD=41|OwnerIndex=789|IndexInSheet=41|OwnerPartId=-1|Location.X=622|Location.Y=558|Color=8388608|FontID=1|IsHidden=T|Text=Gold|Name=Center Contact Plating
|RECORD=41|OwnerIndex=789|IndexInSheet=42|OwnerPartId=-1|Location.X=622|Location.Y=558|Color=8388608|FontID=1|IsHidden=T|Text=Rev. C, 06/2010|Name=Datasheet Version
|RECORD=41|OwnerIndex=789|IndexInSheet=43|OwnerPartId=-1|Location.X=622|Location.Y=558|Color=8388608|FontID=1|IsHidden=T|Text=-|Name=Ingress Protection
|RECORD=34|OwnerIndex=789|IndexInSheet=-1|OwnerPartId=-1|Location.X=633|Location.Y=558|Color=8388608|FontID=1|Text=AN2|Name=Designator|ReadOnlyState=1
|RECORD=41|OwnerIndex=789|IndexInSheet=-1|OwnerPartId=-1|Location.X=684|Location.Y=507|Color=8388608|FontID=1|Text=RF2-49B-T-00-50-G-HDW|Name=Comment
|RECORD=44|OwnerIndex=789
|RECORD=45|OwnerIndex=841|IndexInSheet=-1|Description=THD, 5-Leads, Body 7x7mm, Pitch 2.54mm|UseComponentLibrary=T|ModelName=AMPH-901-143-6RFX_V|ModelType=PCBLIB|DatafileCount=1|ModelDatafileEntity0=AMPH-901-143-6RFX_V|ModelDatafileKind0=PCBLib|IsCurrent=T|DatalinksLocked=T|DatabaseDatalinksLocked=T
|RECORD=46|OwnerIndex=842
|RECORD=48|OwnerIndex=842
|RECORD=41|OwnerIndex=844|IndexInSheet=-1|OwnerPartId=-1|Color=8388608|FontID=1|Text=2D|Name=Available Preview Images
|RECORD=17|IndexInSheet=77|OwnerPartId=-1|Style=4|ShowNetName=T|Location.X=704|Location.Y=577|Orientation=3|Color=128|FontID=1|Text=GND
|RECORD=1|LibReference=RES-2|ComponentDescription=General Purpose Chip Resistor, 49.9 Ohm, +/- 1%, -55 to 155 degC, 0603 (1608 Metric), RoHS, Tape and Reel|PartCount=2|DisplayModeCount=1|IndexInSheet=78|OwnerPartId=-1|Location.X=539|Location.Y=617|CurrentPartId=1|LibraryPath=*|SourceLibraryName=Altium Content Vault|TargetFileName=*|AreaColor=11599871|Color=128|PartIDLocked=T|DesignItemId=CMP-1659-00036-1|AllPinCount=2
|RECORD=2|OwnerIndex=847|OwnerPartId=1|FormalType=1|Electrical=4|PinConglomerate=32|PinLength=10|Location.X=559|Location.Y=617|Name=2|Designator=2|PinPropagationDelay=0.000000E+000
|RECORD=2|OwnerIndex=847|OwnerPartId=1|FormalType=1|Electrical=4|PinConglomerate=34|PinLength=10|Location.X=539|Location.Y=617|Name=1|Designator=1|PinPropagationDelay=0.000000E+000
|RECORD=6|OwnerIndex=847|IsNotAccesible=T|IndexInSheet=2|OwnerPartId=1|LineWidth=1|Color=16711680|LocationCount=10|X1=559|Y1=617|X2=555|Y2=617|X3=554|Y3=615|X4=552|Y4=619|X5=550|Y5=615|X6=548|Y6=619|X7=546|Y7=615|X8=544|Y8=619|X9=543|Y9=617|X10=539|Y10=617
|RECORD=41|OwnerIndex=847|IndexInSheet=3|OwnerPartId=-1|Location.X=527|Location.Y=632|Color=8388608|FontID=1|IsHidden=T|Text=0603|Name=PackageReference
|RECORD=41|OwnerIndex=847|IndexInSheet=4|OwnerPartId=-1|Location.X=527|Location.Y=632|Color=8388608|FontID=1|IsHidden=T|Text=Tray|Name=Packaging
|RECORD=41|OwnerIndex=847|IndexInSheet=5|OwnerPartId=-1|Location.X=527|Location.Y=632|Color=8388608|FontID=1|IsHidden=T|Text=Datasheet|Name=ComponentLink2Description
|RECORD=41|OwnerIndex=847|IndexInSheet=6|OwnerPartId=-1|Location.X=527|Location.Y=632|Color=8388608|FontID=1|IsHidden=T|Text=Manufacturer URL|Name=ComponentLink1Description
|RECORD=41|OwnerIndex=847|IndexInSheet=7|OwnerPartId=-1|Location.X=527|Location.Y=632|Color=8388608|FontID=3|IsHidden=T|Text=https://datasheet.ciiva.com/11808/0900766b80f96399-11808223.pdf|Name=ComponentLink2URL
|RECORD=41|OwnerIndex=847|IndexInSheet=8|OwnerPartId=-1|Location.X=527|Location.Y=632|Color=8388608|FontID=1|IsHidden=T|Text=true|Name=RoHSCompliant
|RECORD=41|OwnerIndex=847|IndexInSheet=9|OwnerPartId=-1|Location.X=527|Location.Y=632|Color=8388608|FontID=1|IsHidden=T|Text=85 degC|Name=Max Operating Temperature
|RECORD=41|OwnerIndex=847|IndexInSheet=10|OwnerPartId=-1|Location.X=527|Location.Y=632|Color=8388608|FontID=1|IsHidden=T|Text=3.63 V|Name=Max Supply Voltage
|RECORD=41|OwnerIndex=847|IndexInSheet=11|OwnerPartId=-1|Location.X=527|Location.Y=632|Color=8388608|FontID=3|IsHidden=T|Text=http://www.yageo.com/|Name=ComponentLink1URL
|RECORD=41|OwnerIndex=847|IndexInSheet=12|OwnerPartId=-1|Location.X=527|Location.Y=632|Color=8388608|FontID=1|IsHidden=T|Text=2-Pin Surface Mount Device, Body 1.6 x 0.8 mm|Name=PackageDescription
|RECORD=41|OwnerIndex=847|IndexInSheet=13|OwnerPartId=-1|Location.X=527|Location.Y=632|Color=8388608|FontID=1|IsHidden=T|Text=LQFP|Name=Case\Package
|RECORD=41|OwnerIndex=847|IndexInSheet=14|OwnerPartId=-1|Location.X=527|Location.Y=632|Color=8388608|FontID=1|IsHidden=T|Text=Rev. 4, 04/2009|Name=DatasheetVersion
|RECORD=41|OwnerIndex=847|IndexInSheet=15|OwnerPartId=-1|Location.X=527|Location.Y=632|Color=8388608|FontID=1|IsHidden=T|Text=-40 degC|Name=Min Operating Temperature
|RECORD=41|OwnerIndex=847|IndexInSheet=16|OwnerPartId=-1|Location.X=527|Location.Y=632|Color=8388608|FontID=1|IsHidden=T|Text=SPI|Name=Interface
|RECORD=41|OwnerIndex=847|IndexInSheet=17|OwnerPartId=-1|Location.X=527|Location.Y=632|Color=8388608|FontID=1|IsHidden=T|Text=250|Name=Package Quantity
|RECORD=41|OwnerIndex=847|IndexInSheet=18|OwnerPartId=-1|Location.X=527|Location.Y=632|Color=8388608|FontID=1|IsHidden=T|Text=2.97 V|Name=Min Supply Voltage
|RECORD=41|OwnerIndex=847|IndexInSheet=19|OwnerPartId=-1|Location.X=527|Location.Y=632|Color=8388608|FontID=1|IsHidden=T|Text=48|Name=Pins
|RECORD=34|OwnerIndex=847|IndexInSheet=-1|OwnerPartId=-1|Location.X=538|Location.Y=620|Color=8388608|FontID=1|Text=R33|Name=Designator|ReadOnlyState=1
|RECORD=41|OwnerIndex=847|IndexInSheet=-1|OwnerPartId=-1|Location.X=538|Location.Y=604|Color=8388608|FontID=1|Text=49.9R|Name=Comment
|RECORD=44|OwnerIndex=847
|RECORD=45|OwnerIndex=872|IndexInSheet=-1|Description=Chip Resistor, 2-Leads, Body 1.70x0.90mm, IPC Medium Density|UseComponentLibrary=T|ModelName=RESC1608X55X25NL10T15|ModelType=PCBLIB|DatafileCount=1|ModelDatafileEntity0=RESC1608X55X25NL10T15|ModelDatafileKind0=PCBLib|IsCurrent=T|DatalinksLocked=T|DatabaseDatalinksLocked=T
|RECORD=46|OwnerIndex=873
|RECORD=48|OwnerIndex=873
|RECORD=41|OwnerIndex=875|IndexInSheet=-1|OwnerPartId=-1|Color=8388608|FontID=1|IsHidden=T|Text=2D|Name=Available Preview Images
|RECORD=45|OwnerIndex=872|IndexInSheet=-1|Description=Chip Resistor, 2-Leads, Body 1.70x0.90mm, IPC Low Density|UseComponentLibrary=T|ModelName=RESC1608X55X25ML10T15|ModelType=PCBLIB|DatafileCount=1|ModelDatafileEntity0=RESC1608X55X25ML10T15|ModelDatafileKind0=PCBLib|DatalinksLocked=T|DatabaseDatalinksLocked=T
|RECORD=46|OwnerIndex=877
|RECORD=48|OwnerIndex=877
|RECORD=41|OwnerIndex=879|IndexInSheet=-1|OwnerPartId=-1|Color=8388608|FontID=1|IsHidden=T|Text=2D|Name=Available Preview Images
|RECORD=45|OwnerIndex=872|IndexInSheet=-1|Description=Chip Resistor, 2-Leads, Body 1.70x0.90mm, IPC High Density|UseComponentLibrary=T|ModelName=RESC1608X55X25LL10T15|ModelType=PCBLIB|DatafileCount=1|ModelDatafileEntity0=RESC1608X55X25LL10T15|ModelDatafileKind0=PCBLib|DatalinksLocked=T|DatabaseDatalinksLocked=T
|RECORD=46|OwnerIndex=881
|RECORD=48|OwnerIndex=881
|RECORD=41|OwnerIndex=883|IndexInSheet=-1|OwnerPartId=-1|Color=8388608|FontID=1|IsHidden=T|Text=2D|Name=Available Preview Images
|RECORD=17|IndexInSheet=79|OwnerPartId=-1|ShowNetName=T|Location.X=264|Location.Y=617|Orientation=2|Color=255|FontID=1|Text=ANT2_OUT|IsCrossSheetConnector=T
|RECORD=17|IndexInSheet=80|OwnerPartId=-1|ShowNetName=T|Location.X=270|Location.Y=720|Orientation=1|Color=128|FontID=1|Text=+3.3V
|RECORD=17|IndexInSheet=81|OwnerPartId=-1|ShowNetName=T|Location.X=300|Location.Y=720|Orientation=1|Color=128|FontID=1|Text=+3.3V
|RECORD=17|IndexInSheet=82|OwnerPartId=-1|ShowNetName=T|Location.X=264|Location.Y=562|Orientation=2|Color=255|FontID=1|Text=ANT2_IN|IsCrossSheetConnector=T
|RECORD=17|IndexInSheet=83|OwnerPartId=-1|Style=4|ShowNetName=T|Location.X=384|Location.Y=487|Orientation=3|Color=128|FontID=1|Text=GND
|RECORD=17|IndexInSheet=84|OwnerPartId=-1|Style=4|ShowNetName=T|Location.X=334|Location.Y=487|Orientation=3|Color=128|FontID=1|Text=GND
|RECORD=17|IndexInSheet=85|OwnerPartId=-1|ShowNetName=T|Location.X=334|Location.Y=707|Orientation=1|Color=128|FontID=1|Text=+3.3V
|RECORD=1|LibReference=WE-TVS-HS-4|ComponentDescription=TVS Diode WE-TVS-HS, VRWM=3.3V|PartCount=2|DisplayModeCount=1|IndexInSheet=86|OwnerPartId=-1|Location.X=1334|Location.Y=757|Orientation=1|CurrentPartId=1|LibraryPath=*|SourceLibraryName=Altium Content Vault|TargetFileName=*|AreaColor=11599871|Color=128|PartIDLocked=F|DesignItemId=CMP-1486-00002-1|AllPinCount=4
|RECORD=14|OwnerIndex=892|IsNotAccesible=T|OwnerPartId=1|Location.X=1328|Location.Y=734|Corner.X=1368|Corner.Y=772|AreaColor=11599871|IsSolid=T|Transparent=T
|RECORD=6|OwnerIndex=892|IsNotAccesible=T|IndexInSheet=1|OwnerPartId=1|LineWidth=1|Color=16711680|LocationCount=4|X1=1338|X1_Frac=10000|Y1=758|Y1_Frac=40000|X2=1336|X2_Frac=10000|Y2=756|Y2_Frac=40000|X3=1332|X3_Frac=10000|Y3=756|Y3_Frac=40000|X4=1330|X4_Frac=10000|Y4=754|Y4_Frac=40000
|RECORD=7|OwnerIndex=892|IsNotAccesible=T|IndexInSheet=2|OwnerPartId=1|LineWidth=1|Color=16711680|AreaColor=16711680|IsSolid=T|LocationCount=3|X1=1338|X1_Frac=90000|Y1=750|Y1_Frac=50000|X2=1333|X2_Frac=90000|Y2=755|Y2_Frac=50000|X3=1328|X3_Frac=90000|Y3=750|Y3_Frac=50000
|RECORD=12|OwnerIndex=892|IsNotAccesible=T|IndexInSheet=3|OwnerPartId=1|Location.X=1345|Location.Y=755|Radius_Frac=63392|LineWidth=1|StartAngle=57.394|EndAngle=30.947
|RECORD=6|OwnerIndex=892|IsNotAccesible=T|IndexInSheet=4|OwnerPartId=1|LineWidth=1|LocationCount=2|X1=1354|Y1=755|X2=1345|Y2=755
|RECORD=7|OwnerIndex=892|IsNotAccesible=T|IndexInSheet=5|OwnerPartId=1|LineWidth=1|Color=16711680|AreaColor=16711680|LocationCount=3|X1=1349|X1_Frac=90000|Y1=742|Y1_Frac=50000|X2=1344|X2_Frac=90000|Y2=747|Y2_Frac=50000|X3=1339|X3_Frac=90000|Y3=742|Y3_Frac=50000
|RECORD=6|OwnerIndex=892|IsNotAccesible=T|IndexInSheet=6|OwnerPartId=1|LineWidth=1|Color=16711680|LocationCount=2|X1=1341|Y1=748|X2=1348|X2_Frac=87402|Y2=748
|RECORD=7|OwnerIndex=892|IsNotAccesible=T|IndexInSheet=7|OwnerPartId=1|LineWidth=1|Color=16711680|AreaColor=16711680|LocationCount=3|X1=1349|X1_Frac=90000|Y1=758|Y1_Frac=50000|X2=1344|X2_Frac=90000|Y2=763|Y2_Frac=50000|X3=1339|X3_Frac=90000|Y3=758|Y3_Frac=50000
|RECORD=6|OwnerIndex=892|IsNotAccesible=T|IndexInSheet=8|OwnerPartId=1|LineWidth=1|Color=16711680|LocationCount=2|X1=1341|Y1=764|X2=1348|X2_Frac=87402|Y2=764
|RECORD=6|OwnerIndex=892|IsNotAccesible=T|IndexInSheet=9|OwnerPartId=1|LineWidth=1|LocationCount=2|X1=1345|Y1=748|X2=1345|Y2=758
|RECORD=6|OwnerIndex=892|IsNotAccesible=T|IndexInSheet=10|OwnerPartId=1|LineWidth=1|LocationCount=2|X1=1345|Y1=764|X2=1345|Y2=770
|RECORD=6|OwnerIndex=892|IsNotAccesible=T|IndexInSheet=11|OwnerPartId=1|LineWidth=1|LocationCount=2|X1=1334|Y1=757|X2=1334|Y2=770
|RECORD=6|OwnerIndex=892|IsNotAccesible=T|IndexInSheet=12|OwnerPartId=1|LineWidth=1|LocationCount=2|X1=1334|Y1=736|X2=1334|Y2=750
|RECORD=6|OwnerIndex=892|IsNotAccesible=T|IndexInSheet=13|OwnerPartId=1|LineWidth=1|LocationCount=2|X1=1345|Y1=736|X2=1345|Y2=742
|RECORD=6|OwnerIndex=892|IsNotAccesible=T|IndexInSheet=14|OwnerPartId=1|LineWidth=1|LocationCount=2|X1=1334|Y1=736|X2=1362|Y2=736
|RECORD=6|OwnerIndex=892|IsNotAccesible=T|IndexInSheet=15|OwnerPartId=1|LineWidth=1|LocationCount=2|X1=1334|Y1=770|X2=1362|Y2=770
|RECORD=6|OwnerIndex=892|IsNotAccesible=T|IndexInSheet=16|OwnerPartId=1|LineWidth=1|LocationCount=2|X1=1354|Y1=751|X2=1354|Y2=737
|RECORD=2|OwnerIndex=892|OwnerPartId=1|FormalType=1|Electrical=4|PinConglomerate=51|PinLength=10|Location.X=1334|Location.Y=737|Name=GND|Designator=1|PinPropagationDelay=0.000000E+000
|RECORD=2|OwnerIndex=892|OwnerPartId=1|FormalType=1|Electrical=4|PinConglomerate=51|PinLength=10|Location.X=1354|Location.Y=737|Name=I/O1|Designator=2|PinPropagationDelay=0.000000E+000
|RECORD=2|OwnerIndex=892|OwnerPartId=1|FormalType=1|Electrical=4|PinConglomerate=49|PinLength=10|Location.X=1354|Location.Y=767|Name=I/O2|Designator=3|PinPropagationDelay=0.000000E+000
|RECORD=2|OwnerIndex=892|OwnerPartId=1|FormalType=1|Electrical=4|PinConglomerate=49|PinLength=10|Location.X=1334|Location.Y=767|Name=VDD|Designator=4|PinPropagationDelay=0.000000E+000
|RECORD=12|OwnerIndex=892|IsNotAccesible=T|IndexInSheet=21|OwnerPartId=1|Location.X=1334|Location.Y=770|Radius_Frac=63392|LineWidth=1|StartAngle=57.394|EndAngle=30.947
|RECORD=12|OwnerIndex=892|IsNotAccesible=T|IndexInSheet=22|OwnerPartId=1|Location.X=1334|Location.Y=736|Radius_Frac=63392|LineWidth=1|StartAngle=57.394|EndAngle=30.947
|RECORD=12|OwnerIndex=892|IsNotAccesible=T|IndexInSheet=23|OwnerPartId=1|Location.X=1362|Location.Y=751|Radius_Frac=63392|LineWidth=1|StartAngle=57.394|EndAngle=30.947
|RECORD=6|OwnerIndex=892|IsNotAccesible=T|IndexInSheet=24|OwnerPartId=1|LineWidth=1|LocationCount=2|X1=1354|Y1=751|X2=1362|Y2=751
|RECORD=7|OwnerIndex=892|IsNotAccesible=T|IndexInSheet=25|OwnerPartId=1|LineWidth=1|Color=16711680|AreaColor=16711680|LocationCount=3|X1=1366|X1_Frac=90000|Y1=742|Y1_Frac=50000|X2=1361|X2_Frac=90000|Y2=747|Y2_Frac=50000|X3=1356|X3_Frac=90000|Y3=742|Y3_Frac=50000
|RECORD=6|OwnerIndex=892|IsNotAccesible=T|IndexInSheet=26|OwnerPartId=1|LineWidth=1|Color=16711680|LocationCount=2|X1=1358|Y1=748|X2=1365|X2_Frac=87402|Y2=748
|RECORD=7|OwnerIndex=892|IsNotAccesible=T|IndexInSheet=27|OwnerPartId=1|LineWidth=1|Color=16711680|AreaColor=16711680|LocationCount=3|X1=1366|X1_Frac=90000|Y1=758|Y1_Frac=50000|X2=1361|X2_Frac=90000|Y2=763|Y2_Frac=50000|X3=1356|X3_Frac=90000|Y3=758|Y3_Frac=50000
|RECORD=6|OwnerIndex=892|IsNotAccesible=T|IndexInSheet=28|OwnerPartId=1|LineWidth=1|Color=16711680|LocationCount=2|X1=1358|Y1=764|X2=1365|X2_Frac=87402|Y2=764
|RECORD=6|OwnerIndex=892|IsNotAccesible=T|IndexInSheet=29|OwnerPartId=1|LineWidth=1|LocationCount=2|X1=1362|Y1=748|X2=1362|Y2=758
|RECORD=6|OwnerIndex=892|IsNotAccesible=T|IndexInSheet=30|OwnerPartId=1|LineWidth=1|LocationCount=2|X1=1362|Y1=764|X2=1362|Y2=770
|RECORD=6|OwnerIndex=892|IsNotAccesible=T|IndexInSheet=31|OwnerPartId=1|LineWidth=1|LocationCount=2|X1=1362|Y1=736|X2=1362|Y2=742
|RECORD=12|OwnerIndex=892|IsNotAccesible=T|IndexInSheet=32|OwnerPartId=1|Location.X=1345|Location.Y=770|Radius_Frac=63392|LineWidth=1|StartAngle=57.394|EndAngle=30.947
|RECORD=12|OwnerIndex=892|IsNotAccesible=T|IndexInSheet=33|OwnerPartId=1|Location.X=1345|Location.Y=736|Radius_Frac=63392|LineWidth=1|StartAngle=57.394|EndAngle=30.947
|RECORD=6|OwnerIndex=892|IsNotAccesible=T|IndexInSheet=34|OwnerPartId=1|LineWidth=1|LocationCount=2|X1=1354|Y1=755|X2=1354|Y2=772
|RECORD=41|OwnerIndex=892|IndexInSheet=35|OwnerPartId=-1|Location.X=1327|Location.X_Frac=90000|Location.Y=779|Color=8388608|FontID=1|IsHidden=T|Text=8240136|Name=PartNumber
|RECORD=41|OwnerIndex=892|IndexInSheet=36|OwnerPartId=-1|Location.X=1327|Location.X_Frac=90000|Location.Y=779|Color=8388608|FontID=1|IsHidden=T|Text=Manufacturer URL|Name=ComponentLink1Description
|RECORD=41|OwnerIndex=892|IndexInSheet=37|OwnerPartId=-1|Location.X=1327|Location.X_Frac=90000|Location.Y=779|Color=8388608|FontID=1|IsHidden=T|Text=Wuerth Elektronik|Name=Manufacturer
|RECORD=41|OwnerIndex=892|IndexInSheet=38|OwnerPartId=-1|Location.X=1327|Location.X_Frac=90000|Location.Y=779|Color=8388608|FontID=1|IsHidden=T|Text=SOT143-4L|Name=PackageReference
|RECORD=41|OwnerIndex=892|IndexInSheet=39|OwnerPartId=-1|Location.X=1327|Location.X_Frac=90000|Location.Y=779|Color=8388608|FontID=3|IsHidden=T|Text=http://www.we-online.com|Name=ComponentLink1URL
|RECORD=41|OwnerIndex=892|IndexInSheet=40|OwnerPartId=-1|Location.X=1327|Location.X_Frac=90000|Location.Y=779|Color=8388608|FontID=1|IsHidden=T|Text=3.3V|Name=Reverse Stand Off Voltage
|RECORD=41|OwnerIndex=892|IndexInSheet=41|OwnerPartId=-1|Location.X=1327|Location.X_Frac=90000|Location.Y=779|Color=8388608|FontID=1|IsHidden=T|Text=Datasheet|Name=ComponentLink2Description
|RECORD=41|OwnerIndex=892|IndexInSheet=42|OwnerPartId=-1|Location.X=1327|Location.X_Frac=90000|Location.Y=779|Color=8388608|FontID=3|IsHidden=T|Text=http://katalog.we-online.de/kataloge/eisos/media/pdf/8240136.pdf|Name=ComponentLink2URL
|RECORD=34|OwnerIndex=892|IndexInSheet=-1|OwnerPartId=-1|Location.X=1368|Location.Y=763|Color=8388608|FontID=1|Text=D2|Name=Designator|ReadOnlyState=1
|RECORD=41|OwnerIndex=892|IndexInSheet=-1|OwnerPartId=-1|Location.X=1368|Location.Y=753|Color=8388608|FontID=1|Text=8240136|Name=Comment
|RECORD=44|OwnerIndex=892
|RECORD=45|OwnerIndex=942|IndexInSheet=-1|Description=SOT143-4L, 4-Leads, Body 2.95x2.4mm, Pitch 1.70/1.90mm|UseComponentLibrary=T|ModelName=SOT143-4L|ModelType=PCBLIB|DatafileCount=1|ModelDatafileEntity0=SOT143-4L|ModelDatafileKind0=PCBLib|IsCurrent=T|DatalinksLocked=T|DatabaseDatalinksLocked=T
|RECORD=46|OwnerIndex=943
|RECORD=48|OwnerIndex=943
|RECORD=41|OwnerIndex=945|IndexInSheet=-1|OwnerPartId=-1|Color=8388608|FontID=1|IsHidden=T|Text=2D|Name=Available Preview Images
|RECORD=17|IndexInSheet=87|OwnerPartId=-1|ShowNetName=T|Location.X=574|Location.Y=797|Orientation=1|Color=128|FontID=1|Text=+3.3V
|RECORD=17|IndexInSheet=88|OwnerPartId=-1|Style=4|ShowNetName=T|Location.X=574|Location.Y=707|Orientation=3|Color=128|FontID=1|Text=GND
|RECORD=17|IndexInSheet=89|OwnerPartId=-1|ShowNetName=T|Location.X=1334|Location.Y=797|Orientation=1|Color=128|FontID=1|Text=+3.3V
|RECORD=17|IndexInSheet=90|OwnerPartId=-1|Style=4|ShowNetName=T|Location.X=1334|Location.Y=707|Orientation=3|Color=128|FontID=1|Text=GND
|RECORD=4|IndexInSheet=91|OwnerPartId=-1|Location.X=727|Location.Y=1022|Color=8388608|FontID=8|Text=INPUT/OUTPUT SIGNALS
|RECORD=17|IndexInSheet=92|OwnerPartId=-1|ShowNetName=T|Location.X=204|Location.Y=972|Orientation=2|Color=255|FontID=1|Text=ANT1_IO_OUT|IsCrossSheetConnector=T
|RECORD=17|IndexInSheet=93|OwnerPartId=-1|ShowNetName=T|Location.X=204|Location.Y=917|Orientation=2|Color=255|FontID=1|Text=ANT1_IO_IN|IsCrossSheetConnector=T
|RECORD=17|IndexInSheet=94|OwnerPartId=-1|ShowNetName=T|Location.X=204|Location.Y=642|Orientation=2|Color=255|FontID=1|Text=ANT2_IO_OUT|IsCrossSheetConnector=T
|RECORD=17|IndexInSheet=95|OwnerPartId=-1|ShowNetName=T|Location.X=204|Location.Y=587|Orientation=2|Color=255|FontID=1|Text=ANT2_IO_IN|IsCrossSheetConnector=T
|RECORD=17|IndexInSheet=96|OwnerPartId=-1|ShowNetName=T|Location.X=964|Location.Y=972|Orientation=2|Color=255|FontID=1|Text=ANT3_IO_OUT|IsCrossSheetConnector=T
|RECORD=17|IndexInSheet=97|OwnerPartId=-1|ShowNetName=T|Location.X=964|Location.Y=917|Orientation=2|Color=255|FontID=1|Text=ANT3_IO_IN|IsCrossSheetConnector=T
|RECORD=17|IndexInSheet=98|OwnerPartId=-1|ShowNetName=T|Location.X=964|Location.Y=642|Orientation=2|Color=255|FontID=1|Text=ANT4_IO_OUT|IsCrossSheetConnector=T
|RECORD=17|IndexInSheet=99|OwnerPartId=-1|ShowNetName=T|Location.X=964|Location.Y=587|Orientation=2|Color=255|FontID=1|Text=ANT4_IO_IN|IsCrossSheetConnector=T
|RECORD=27|IndexInSheet=100|OwnerPartId=-1|LineWidth=1|Color=8388608|LocationCount=2|X1=664|Y1=837|X2=664|Y2=822
|RECORD=27|IndexInSheet=101|OwnerPartId=-1|LineWidth=1|Color=8388608|LocationCount=2|X1=654|Y1=837|X2=654|Y2=822
|RECORD=27|IndexInSheet=102|OwnerPartId=-1|LineWidth=1|Color=8388608|LocationCount=3|X1=674|Y1=822|X2=704|Y2=822|X3=704|Y3=817
|RECORD=27|IndexInSheet=103|OwnerPartId=-1|LineWidth=1|Color=8388608|LocationCount=2|X1=624|Y1=867|X2=594|Y2=867
|RECORD=27|IndexInSheet=104|OwnerPartId=-1|LineWidth=1|Color=8388608|LocationCount=2|X1=300|Y1=1000|X2=300|Y2=920
|RECORD=27|IndexInSheet=105|OwnerPartId=-1|LineWidth=1|Color=8388608|LocationCount=4|X1=644|Y1=917|X2=664|Y2=917|X3=704|Y3=917|X4=704|Y4=907
|RECORD=27|IndexInSheet=106|OwnerPartId=-1|LineWidth=1|Color=8388608|LocationCount=3|X1=504|Y1=892|X2=514|Y2=892|X3=514|Y3=947
|RECORD=27|IndexInSheet=107|OwnerPartId=-1|LineWidth=1|Color=8388608|LocationCount=3|X1=394|Y1=862|X2=384|Y2=862|X3=384|Y3=817
|RECORD=27|IndexInSheet=108|OwnerPartId=-1|LineWidth=1|Color=8388608|LocationCount=2|X1=334|Y1=817|X2=334|Y2=827
|RECORD=27|IndexInSheet=109|OwnerPartId=-1|LineWidth=1|Color=8388608|LocationCount=2|X1=334|Y1=872|X2=334|Y2=1037
|RECORD=27|IndexInSheet=110|OwnerPartId=-1|LineWidth=1|Color=8388608|LocationCount=2|X1=1424|Y1=837|X2=1424|Y2=822
|RECORD=27|IndexInSheet=111|OwnerPartId=-1|LineWidth=1|Color=8388608|LocationCount=2|X1=1414|Y1=837|X2=1414|Y2=822
|RECORD=27|IndexInSheet=112|OwnerPartId=-1|LineWidth=1|Color=8388608|LocationCount=3|X1=1434|Y1=822|X2=1464|Y2=822|X3=1464|Y3=817
|RECORD=27|IndexInSheet=113|OwnerPartId=-1|LineWidth=1|Color=8388608|LocationCount=2|X1=1384|Y1=867|X2=1354|Y2=867
|RECORD=27|IndexInSheet=114|OwnerPartId=-1|LineWidth=1|Color=8388608|LocationCount=2|X1=1030|Y1=995|X2=1030|Y2=970
|RECORD=27|IndexInSheet=115|OwnerPartId=-1|LineWidth=1|Color=8388608|LocationCount=4|X1=1404|Y1=917|X2=1424|Y2=917|X3=1464|Y3=917|X4=1464|Y4=907
|RECORD=27|IndexInSheet=116|OwnerPartId=-1|LineWidth=1|Color=8388608|LocationCount=3|X1=1264|Y1=892|X2=1274|Y2=892|X3=1274|Y3=947
|RECORD=27|IndexInSheet=117|OwnerPartId=-1|LineWidth=1|Color=8388608|LocationCount=3|X1=1154|Y1=862|X2=1144|Y2=862|X3=1144|Y3=817
|RECORD=27|IndexInSheet=118|OwnerPartId=-1|LineWidth=1|Color=8388608|LocationCount=2|X1=1094|Y1=817|X2=1094|Y2=827
|RECORD=27|IndexInSheet=119|OwnerPartId=-1|LineWidth=1|Color=8388608|LocationCount=2|X1=1094|Y1=872|X2=1094|Y2=1037
|RECORD=27|IndexInSheet=120|OwnerPartId=-1|LineWidth=1|Color=8388608|LocationCount=2|X1=1424|Y1=507|X2=1424|Y2=492
|RECORD=27|IndexInSheet=121|OwnerPartId=-1|LineWidth=1|Color=8388608|LocationCount=2|X1=1414|Y1=507|X2=1414|Y2=492
|RECORD=27|IndexInSheet=122|OwnerPartId=-1|LineWidth=1|Color=8388608|LocationCount=3|X1=1434|Y1=492|X2=1464|Y2=492|X3=1464|Y3=487
|RECORD=27|IndexInSheet=123|OwnerPartId=-1|LineWidth=1|Color=8388608|LocationCount=4|X1=1404|Y1=587|X2=1424|Y2=587|X3=1464|Y3=587|X4=1464|Y4=577
|RECORD=27|IndexInSheet=124|OwnerPartId=-1|LineWidth=1|Color=8388608|LocationCount=3|X1=1264|Y1=562|X2=1274|Y2=562|X3=1274|Y3=617
|RECORD=27|IndexInSheet=125|OwnerPartId=-1|LineWidth=1|Color=8388608|LocationCount=3|X1=1154|Y1=542|X2=1094|Y2=542|X3=1094|Y3=527
|RECORD=27|IndexInSheet=126|OwnerPartId=-1|LineWidth=1|Color=8388608|LocationCount=3|X1=1154|Y1=532|X2=1144|Y2=532|X3=1144|Y3=487
|RECORD=27|IndexInSheet=127|OwnerPartId=-1|LineWidth=1|Color=8388608|LocationCount=2|X1=1094|Y1=542|X2=1094|Y2=707
|RECORD=27|IndexInSheet=128|OwnerPartId=-1|LineWidth=1|Color=8388608|LocationCount=2|X1=664|Y1=507|X2=664|Y2=492
|RECORD=27|IndexInSheet=129|OwnerPartId=-1|LineWidth=1|Color=8388608|LocationCount=2|X1=654|Y1=507|X2=654|Y2=492
|RECORD=27|IndexInSheet=130|OwnerPartId=-1|LineWidth=1|Color=8388608|LocationCount=3|X1=674|Y1=492|X2=704|Y2=492|X3=704|Y3=487
|RECORD=27|IndexInSheet=131|OwnerPartId=-1|LineWidth=1|Color=8388608|LocationCount=4|X1=644|Y1=587|X2=664|Y2=587|X3=704|Y3=587|X4=704|Y4=577
|RECORD=27|IndexInSheet=132|OwnerPartId=-1|LineWidth=1|Color=8388608|LocationCount=3|X1=504|Y1=562|X2=514|Y2=562|X3=514|Y3=617
|RECORD=27|IndexInSheet=133|OwnerPartId=-1|LineWidth=1|Color=8388608|LocationCount=3|X1=394|Y1=532|X2=384|Y2=532|X3=384|Y3=487
|RECORD=27|IndexInSheet=134|OwnerPartId=-1|LineWidth=1|Color=8388608|LocationCount=2|X1=334|Y1=487|X2=334|Y2=497
|RECORD=27|IndexInSheet=135|OwnerPartId=-1|LineWidth=1|Color=8388608|LocationCount=2|X1=334|Y1=542|X2=334|Y2=707
|RECORD=27|IndexInSheet=136|OwnerPartId=-1|LineWidth=1|Color=8388608|LocationCount=2|X1=594|Y1=777|X2=594|Y2=867
|RECORD=27|IndexInSheet=137|OwnerPartId=-1|LineWidth=1|Color=8388608|LocationCount=2|X1=594|Y1=727|X2=594|Y2=617
|RECORD=27|IndexInSheet=138|OwnerPartId=-1|LineWidth=1|Color=8388608|LocationCount=2|X1=1354|Y1=777|X2=1354|Y2=867
|RECORD=27|IndexInSheet=139|OwnerPartId=-1|LineWidth=1|Color=8388608|LocationCount=2|X1=1354|Y1=727|X2=1354|Y2=617
|RECORD=27|IndexInSheet=140|OwnerPartId=-1|LineWidth=1|Color=8388608|LocationCount=2|X1=574|Y1=777|X2=574|Y2=797
|RECORD=27|IndexInSheet=141|OwnerPartId=-1|LineWidth=1|Color=8388608|LocationCount=2|X1=574|Y1=707|X2=574|Y2=727
|RECORD=27|IndexInSheet=142|OwnerPartId=-1|LineWidth=1|Color=8388608|LocationCount=2|X1=1334|Y1=777|X2=1334|Y2=797
|RECORD=27|IndexInSheet=143|OwnerPartId=-1|LineWidth=1|Color=8388608|LocationCount=2|X1=1334|Y1=707|X2=1334|Y2=727
|RECORD=27|IndexInSheet=144|OwnerPartId=-1|LineWidth=1|Color=8388608|LocationCount=2|X1=394|Y1=562|X2=264|Y2=562
|RECORD=27|IndexInSheet=145|OwnerPartId=-1|LineWidth=1|Color=8388608|LocationCount=2|X1=264|Y1=617|X2=394|Y2=617
|RECORD=27|IndexInSheet=146|OwnerPartId=-1|LineWidth=1|Color=8388608|LocationCount=2|X1=394|Y1=892|X2=264|Y2=892
|RECORD=27|IndexInSheet=147|OwnerPartId=-1|LineWidth=1|Color=8388608|LocationCount=2|X1=264|Y1=947|X2=394|Y2=947
|RECORD=27|IndexInSheet=148|OwnerPartId=-1|LineWidth=1|Color=8388608|LocationCount=3|X1=624|Y1=537|X2=594|Y2=537|X3=594|Y3=617
|RECORD=27|IndexInSheet=149|OwnerPartId=-1|LineWidth=1|Color=8388608|LocationCount=2|X1=1154|Y1=562|X2=1024|Y2=562
|RECORD=27|IndexInSheet=150|OwnerPartId=-1|LineWidth=1|Color=8388608|LocationCount=2|X1=1024|Y1=617|X2=1154|Y2=617
|RECORD=27|IndexInSheet=151|OwnerPartId=-1|LineWidth=1|Color=8388608|LocationCount=2|X1=1154|Y1=892|X2=1024|Y2=892
|RECORD=27|IndexInSheet=152|OwnerPartId=-1|LineWidth=1|Color=8388608|LocationCount=2|X1=1024|Y1=947|X2=1154|Y2=947
|RECORD=27|IndexInSheet=153|OwnerPartId=-1|LineWidth=1|Color=8388608|LocationCount=3|X1=1384|Y1=537|X2=1354|Y2=537|X3=1354|Y3=617
|RECORD=27|IndexInSheet=154|OwnerPartId=-1|LineWidth=1|Color=8388608|LocationCount=3|X1=394|Y1=587|X2=300|Y2=587|X3=204|Y3=587
|RECORD=27|IndexInSheet=155|OwnerPartId=-1|LineWidth=1|Color=8388608|LocationCount=3|X1=394|Y1=642|X2=270|Y2=642|X3=204|Y3=642
|RECORD=27|IndexInSheet=156|OwnerPartId=-1|LineWidth=1|Color=8388608|LocationCount=3|X1=504|Y1=617|X2=514|Y2=617|X3=529|Y3=617
|RECORD=27|IndexInSheet=157|OwnerPartId=-1|LineWidth=1|Color=8388608|LocationCount=3|X1=504|Y1=947|X2=514|Y2=947|X3=529|Y3=947
|RECORD=27|IndexInSheet=158|OwnerPartId=-1|LineWidth=1|Color=8388608|LocationCount=3|X1=1154|Y1=587|X2=1060|Y2=587|X3=964|Y3=587
|RECORD=27|IndexInSheet=159|OwnerPartId=-1|LineWidth=1|Color=8388608|LocationCount=3|X1=1154|Y1=642|X2=1030|Y2=642|X3=964|Y3=642
|RECORD=27|IndexInSheet=160|OwnerPartId=-1|LineWidth=1|Color=8388608|LocationCount=3|X1=1264|Y1=617|X2=1274|Y2=617|X3=1289|Y3=617
|RECORD=27|IndexInSheet=161|OwnerPartId=-1|LineWidth=1|Color=8388608|LocationCount=3|X1=1264|Y1=947|X2=1274|Y2=947|X3=1289|Y3=947
|RECORD=27|IndexInSheet=162|OwnerPartId=-1|LineWidth=1|Color=8388608|LocationCount=3|X1=1384|Y1=617|X2=1354|Y2=617|X3=1329|Y3=617
|RECORD=27|IndexInSheet=163|OwnerPartId=-1|LineWidth=1|Color=8388608|LocationCount=6|X1=674|Y1=507|X2=674|Y2=492|X3=664|Y3=492|X4=654|Y4=492|X5=644|Y5=492|X6=644|Y6=507
|RECORD=27|IndexInSheet=164|OwnerPartId=-1|LineWidth=1|Color=8388608|LocationCount=6|X1=674|Y1=837|X2=674|Y2=822|X3=664|Y3=822|X4=654|Y4=822|X5=644|Y5=822|X6=644|Y6=837
|RECORD=27|IndexInSheet=165|OwnerPartId=-1|LineWidth=1|Color=8388608|LocationCount=6|X1=1434|Y1=507|X2=1434|Y2=492|X3=1424|Y3=492|X4=1414|Y4=492|X5=1404|Y5=492|X6=1404|Y6=507
|RECORD=27|IndexInSheet=166|OwnerPartId=-1|LineWidth=1|Color=8388608|LocationCount=6|X1=1434|Y1=837|X2=1434|Y2=822|X3=1424|Y3=822|X4=1414|Y4=822|X5=1404|Y5=822|X6=1404|Y6=837
|RECORD=17|IndexInSheet=167|OwnerPartId=-1|Style=4|ShowNetName=T|Location.X=1464|Location.Y=487|Orientation=3|Color=128|FontID=1|Text=GND
|RECORD=1|LibReference=RES|PartCount=2|DisplayModeCount=2|IndexInSheet=168|OwnerPartId=-1|Location.X=280|Location.Y=1030|Orientation=3|CurrentPartId=1|SourceLibraryName=Altium Content Vault|TargetFileName=*|AreaColor=11599871|Color=128|PartIDLocked=F|DesignItemId=CMP-2002-05217-1|AllPinCount=2
|RECORD=2|OwnerIndex=1028|OwnerPartId=1|OwnerPartDisplayMode=1|FormalType=1|Electrical=4|PinConglomerate=35|PinLength=10|Location.X=270|Location.Y=1010|Name=2|Designator=2|PinPropagationDelay=0.000000E+000
|RECORD=2|OwnerIndex=1028|OwnerPartId=1|OwnerPartDisplayMode=1|FormalType=1|Electrical=4|PinConglomerate=33|PinLength=10|Location.X=270|Location.Y=1030|Name=1|Designator=1|PinPropagationDelay=0.000000E+000
|RECORD=14|OwnerIndex=1028|IsNotAccesible=T|IndexInSheet=2|OwnerPartId=1|OwnerPartDisplayMode=1|Location.X=266|Location.Y=1010|Corner.X=274|Corner.Y=1030|LineWidth=1|Color=16711680|AreaColor=11599871
|RECORD=2|OwnerIndex=1028|OwnerPartId=1|FormalType=1|Electrical=4|PinConglomerate=35|PinLength=10|Location.X=270|Location.Y=1010|Name=2|Designator=2|PinPropagationDelay=0.000000E+000
|RECORD=2|OwnerIndex=1028|OwnerPartId=1|FormalType=1|Electrical=4|PinConglomerate=33|PinLength=10|Location.X=270|Location.Y=1030|Name=1|Designator=1|PinPropagationDelay=0.000000E+000
|RECORD=6|OwnerIndex=1028|IsNotAccesible=T|IndexInSheet=5|OwnerPartId=1|LineWidth=1|Color=16711680|LocationCount=10|X1=270|Y1=1010|X2=270|Y2=1014|X3=268|Y3=1015|X4=272|Y4=1017|X5=268|Y5=1019|X6=272|Y6=1021|X7=268|Y7=1023|X8=272|Y8=1025|X9=270|Y9=1026|X10=270|Y10=1030
|RECORD=41|OwnerIndex=1028|IndexInSheet=6|OwnerPartId=-1|Location.X=267|Location.Y=1042|Color=8388608|FontID=1|IsHidden=T|Text=Bourns|Name=Manufacturer
|RECORD=41|OwnerIndex=1028|IndexInSheet=7|OwnerPartId=-1|Location.X=267|Location.Y=1042|Color=8388608|FontID=1|IsHidden=T|Text=CR0402-FX-4701GLF|Name=Part Number
|RECORD=34|OwnerIndex=1028|IndexInSheet=-1|OwnerPartId=-1|Location.X=270|Location.Y=1000|Orientation=1|Color=8388608|FontID=2|Text=R14|Name=Designator|ReadOnlyState=1
|RECORD=41|OwnerIndex=1028|IndexInSheet=-1|OwnerPartId=-1|Location.X=280|Location.Y=990|Orientation=1|Color=8388608|FontID=2|Text=4.7K_1%_0402|Name=Comment
|RECORD=44|OwnerIndex=1028
|RECORD=45|OwnerIndex=1043|IndexInSheet=-1|Description=Chip Resistor, 2-Leads, Body 1.00x0.50mm, IPC Medium Density|UseComponentLibrary=T|ModelName=RESC1005X40X25NL10T10|ModelType=PCBLIB|DatafileCount=1|ModelDatafileEntity0=RESC1005X40X25NL10T10|ModelDatafileKind0=PCBLib|IsCurrent=T|DatalinksLocked=T|DatabaseDatalinksLocked=T
|RECORD=46|OwnerIndex=1044
|RECORD=48|OwnerIndex=1044
|RECORD=41|OwnerIndex=1046|IndexInSheet=-1|OwnerPartId=-1|Color=8388608|FontID=1|IsHidden=T|Text=2D|Name=Available Preview Images
|RECORD=45|OwnerIndex=1043|IndexInSheet=-1|Description=Chip Resistor, 2-Leads, Body 1.00x0.50mm, IPC High Density|UseComponentLibrary=T|ModelName=RESC1005X40X25LL10T10|ModelType=PCBLIB|DatafileCount=1|ModelDatafileEntity0=RESC1005X40X25LL10T10|ModelDatafileKind0=PCBLib|DatalinksLocked=T|DatabaseDatalinksLocked=T
|RECORD=46|OwnerIndex=1048
|RECORD=48|OwnerIndex=1048
|RECORD=41|OwnerIndex=1050|IndexInSheet=-1|OwnerPartId=-1|Color=8388608|FontID=1|IsHidden=T|Text=2D|Name=Available Preview Images
|RECORD=45|OwnerIndex=1043|IndexInSheet=-1|Description=Chip Resistor, 2-Leads, Body 1.00x0.50mm, IPC Low Density|UseComponentLibrary=T|ModelName=RESC1005X40X25ML10T10|ModelType=PCBLIB|DatafileCount=1|ModelDatafileEntity0=RESC1005X40X25ML10T10|ModelDatafileKind0=PCBLib|DatalinksLocked=T|DatabaseDatalinksLocked=T
|RECORD=46|OwnerIndex=1052
|RECORD=48|OwnerIndex=1052
|RECORD=41|OwnerIndex=1054|IndexInSheet=-1|OwnerPartId=-1|Color=8388608|FontID=1|IsHidden=T|Text=2D|Name=Available Preview Images
|RECORD=27|IndexInSheet=169|OwnerPartId=-1|LineWidth=1|Color=8388608|LocationCount=5|X1=394|Y1=972|X2=394|Y2=970|X3=270|Y3=970|X4=204|Y4=970|X5=204|Y5=972
|RECORD=27|IndexInSheet=170|OwnerPartId=-1|LineWidth=1|Color=8388608|LocationCount=5|X1=394|Y1=917|X2=394|Y2=920|X3=300|Y3=920|X4=204|Y4=920|X5=204|Y5=917
|RECORD=1|LibReference=RES|PartCount=2|DisplayModeCount=2|IndexInSheet=171|OwnerPartId=-1|Location.X=310|Location.Y=1030|Orientation=3|CurrentPartId=1|SourceLibraryName=Altium Content Vault|TargetFileName=*|AreaColor=11599871|Color=128|PartIDLocked=F|DesignItemId=CMP-2002-05217-1|AllPinCount=2
|RECORD=2|OwnerIndex=1058|OwnerPartId=1|OwnerPartDisplayMode=1|FormalType=1|Electrical=4|PinConglomerate=35|PinLength=10|Location.X=300|Location.Y=1010|Name=2|Designator=2|PinPropagationDelay=0.000000E+000
|RECORD=2|OwnerIndex=1058|OwnerPartId=1|OwnerPartDisplayMode=1|FormalType=1|Electrical=4|PinConglomerate=33|PinLength=10|Location.X=300|Location.Y=1030|Name=1|Designator=1|PinPropagationDelay=0.000000E+000
|RECORD=14|OwnerIndex=1058|IsNotAccesible=T|IndexInSheet=2|OwnerPartId=1|OwnerPartDisplayMode=1|Location.X=296|Location.Y=1010|Corner.X=304|Corner.Y=1030|LineWidth=1|Color=16711680|AreaColor=11599871
|RECORD=2|OwnerIndex=1058|OwnerPartId=1|FormalType=1|Electrical=4|PinConglomerate=35|PinLength=10|Location.X=300|Location.Y=1010|Name=2|Designator=2|PinPropagationDelay=0.000000E+000
|RECORD=2|OwnerIndex=1058|OwnerPartId=1|FormalType=1|Electrical=4|PinConglomerate=33|PinLength=10|Location.X=300|Location.Y=1030|Name=1|Designator=1|PinPropagationDelay=0.000000E+000
|RECORD=6|OwnerIndex=1058|IsNotAccesible=T|IndexInSheet=5|OwnerPartId=1|LineWidth=1|Color=16711680|LocationCount=10|X1=300|Y1=1010|X2=300|Y2=1014|X3=298|Y3=1015|X4=302|Y4=1017|X5=298|Y5=1019|X6=302|Y6=1021|X7=298|Y7=1023|X8=302|Y8=1025|X9=300|Y9=1026|X10=300|Y10=1030
|RECORD=41|OwnerIndex=1058|IndexInSheet=6|OwnerPartId=-1|Location.X=297|Location.Y=1042|Color=8388608|FontID=1|IsHidden=T|Text=Bourns|Name=Manufacturer
|RECORD=41|OwnerIndex=1058|IndexInSheet=7|OwnerPartId=-1|Location.X=297|Location.Y=1042|Color=8388608|FontID=1|IsHidden=T|Text=CR0402-FX-4701GLF|Name=Part Number
|RECORD=34|OwnerIndex=1058|IndexInSheet=-1|OwnerPartId=-1|Location.X=300|Location.Y=1000|Orientation=1|Color=8388608|FontID=2|Text=R15|Name=Designator|ReadOnlyState=1
|RECORD=41|OwnerIndex=1058|IndexInSheet=-1|OwnerPartId=-1|Location.X=310|Location.Y=990|Orientation=1|Color=8388608|FontID=2|Text=4.7K_1%_0402|Name=Comment
|RECORD=44|OwnerIndex=1058
|RECORD=45|OwnerIndex=1073|IndexInSheet=-1|Description=Chip Resistor, 2-Leads, Body 1.00x0.50mm, IPC Medium Density|UseComponentLibrary=T|ModelName=RESC1005X40X25NL10T10|ModelType=PCBLIB|DatafileCount=1|ModelDatafileEntity0=RESC1005X40X25NL10T10|ModelDatafileKind0=PCBLib|IsCurrent=T|DatalinksLocked=T|DatabaseDatalinksLocked=T
|RECORD=46|OwnerIndex=1074
|RECORD=48|OwnerIndex=1074
|RECORD=41|OwnerIndex=1076|IndexInSheet=-1|OwnerPartId=-1|Color=8388608|FontID=1|IsHidden=T|Text=2D|Name=Available Preview Images
|RECORD=45|OwnerIndex=1073|IndexInSheet=-1|Description=Chip Resistor, 2-Leads, Body 1.00x0.50mm, IPC High Density|UseComponentLibrary=T|ModelName=RESC1005X40X25LL10T10|ModelType=PCBLIB|DatafileCount=1|ModelDatafileEntity0=RESC1005X40X25LL10T10|ModelDatafileKind0=PCBLib|DatalinksLocked=T|DatabaseDatalinksLocked=T
|RECORD=46|OwnerIndex=1078
|RECORD=48|OwnerIndex=1078
|RECORD=41|OwnerIndex=1080|IndexInSheet=-1|OwnerPartId=-1|Color=8388608|FontID=1|IsHidden=T|Text=2D|Name=Available Preview Images
|RECORD=45|OwnerIndex=1073|IndexInSheet=-1|Description=Chip Resistor, 2-Leads, Body 1.00x0.50mm, IPC Low Density|UseComponentLibrary=T|ModelName=RESC1005X40X25ML10T10|ModelType=PCBLIB|DatafileCount=1|ModelDatafileEntity0=RESC1005X40X25ML10T10|ModelDatafileKind0=PCBLib|DatalinksLocked=T|DatabaseDatalinksLocked=T
|RECORD=46|OwnerIndex=1082
|RECORD=48|OwnerIndex=1082
|RECORD=41|OwnerIndex=1084|IndexInSheet=-1|OwnerPartId=-1|Color=8388608|FontID=1|IsHidden=T|Text=2D|Name=Available Preview Images
|RECORD=27|IndexInSheet=172|OwnerPartId=-1|LineWidth=1|Color=8388608|LocationCount=2|X1=300|Y1=1040|X2=300|Y2=1060
|RECORD=27|IndexInSheet=173|OwnerPartId=-1|LineWidth=1|Color=8388608|LocationCount=2|X1=270|Y1=1040|X2=270|Y2=1050
|RECORD=27|IndexInSheet=174|OwnerPartId=-1|LineWidth=1|Color=8388608|LocationCount=2|X1=270|Y1=720|X2=270|Y2=710
|RECORD=27|IndexInSheet=175|OwnerPartId=-1|LineWidth=1|Color=8388608|LocationCount=2|X1=270|Y1=670|X2=270|Y2=642
|RECORD=27|IndexInSheet=176|OwnerPartId=-1|LineWidth=1|Color=8388608|LocationCount=2|X1=300|Y1=670|X2=300|Y2=587
|RECORD=27|IndexInSheet=177|OwnerPartId=-1|LineWidth=1|Color=8388608|LocationCount=2|X1=300|Y1=720|X2=300|Y2=710
|RECORD=1|LibReference=RES|PartCount=2|DisplayModeCount=2|IndexInSheet=178|OwnerPartId=-1|Location.X=280|Location.Y=700|Orientation=3|CurrentPartId=1|SourceLibraryName=Altium Content Vault|TargetFileName=*|AreaColor=11599871|Color=128|PartIDLocked=F|DesignItemId=CMP-2002-05217-1|AllPinCount=2
|RECORD=2|OwnerIndex=1092|OwnerPartId=1|OwnerPartDisplayMode=1|FormalType=1|Electrical=4|PinConglomerate=35|PinLength=10|Location.X=270|Location.Y=680|Name=2|Designator=2|PinPropagationDelay=0.000000E+000
|RECORD=2|OwnerIndex=1092|OwnerPartId=1|OwnerPartDisplayMode=1|FormalType=1|Electrical=4|PinConglomerate=33|PinLength=10|Location.X=270|Location.Y=700|Name=1|Designator=1|PinPropagationDelay=0.000000E+000
|RECORD=14|OwnerIndex=1092|IsNotAccesible=T|IndexInSheet=2|OwnerPartId=1|OwnerPartDisplayMode=1|Location.X=266|Location.Y=680|Corner.X=274|Corner.Y=700|LineWidth=1|Color=16711680|AreaColor=11599871
|RECORD=2|OwnerIndex=1092|OwnerPartId=1|FormalType=1|Electrical=4|PinConglomerate=35|PinLength=10|Location.X=270|Location.Y=680|Name=2|Designator=2|PinPropagationDelay=0.000000E+000
|RECORD=2|OwnerIndex=1092|OwnerPartId=1|FormalType=1|Electrical=4|PinConglomerate=33|PinLength=10|Location.X=270|Location.Y=700|Name=1|Designator=1|PinPropagationDelay=0.000000E+000
|RECORD=6|OwnerIndex=1092|IsNotAccesible=T|IndexInSheet=5|OwnerPartId=1|LineWidth=1|Color=16711680|LocationCount=10|X1=270|Y1=680|X2=270|Y2=684|X3=268|Y3=685|X4=272|Y4=687|X5=268|Y5=689|X6=272|Y6=691|X7=268|Y7=693|X8=272|Y8=695|X9=270|Y9=696|X10=270|Y10=700
|RECORD=41|OwnerIndex=1092|IndexInSheet=6|OwnerPartId=-1|Location.X=267|Location.Y=712|Color=8388608|FontID=1|IsHidden=T|Text=Bourns|Name=Manufacturer
|RECORD=41|OwnerIndex=1092|IndexInSheet=7|OwnerPartId=-1|Location.X=267|Location.Y=712|Color=8388608|FontID=1|IsHidden=T|Text=CR0402-FX-4701GLF|Name=Part Number
|RECORD=34|OwnerIndex=1092|IndexInSheet=-1|OwnerPartId=-1|Location.X=270|Location.Y=670|Orientation=1|Color=8388608|FontID=2|Text=R29|Name=Designator|ReadOnlyState=1
|RECORD=41|OwnerIndex=1092|IndexInSheet=-1|OwnerPartId=-1|Location.X=280|Location.Y=660|Orientation=1|Color=8388608|FontID=2|Text=4.7K_1%_0402|Name=Comment
|RECORD=44|OwnerIndex=1092
|RECORD=45|OwnerIndex=1107|IndexInSheet=-1|Description=Chip Resistor, 2-Leads, Body 1.00x0.50mm, IPC Medium Density|UseComponentLibrary=T|ModelName=RESC1005X40X25NL10T10|ModelType=PCBLIB|DatafileCount=1|ModelDatafileEntity0=RESC1005X40X25NL10T10|ModelDatafileKind0=PCBLib|IsCurrent=T|DatalinksLocked=T|DatabaseDatalinksLocked=T
|RECORD=46|OwnerIndex=1108
|RECORD=48|OwnerIndex=1108
|RECORD=41|OwnerIndex=1110|IndexInSheet=-1|OwnerPartId=-1|Color=8388608|FontID=1|IsHidden=T|Text=2D|Name=Available Preview Images
|RECORD=45|OwnerIndex=1107|IndexInSheet=-1|Description=Chip Resistor, 2-Leads, Body 1.00x0.50mm, IPC High Density|UseComponentLibrary=T|ModelName=RESC1005X40X25LL10T10|ModelType=PCBLIB|DatafileCount=1|ModelDatafileEntity0=RESC1005X40X25LL10T10|ModelDatafileKind0=PCBLib|DatalinksLocked=T|DatabaseDatalinksLocked=T
|RECORD=46|OwnerIndex=1112
|RECORD=48|OwnerIndex=1112
|RECORD=41|OwnerIndex=1114|IndexInSheet=-1|OwnerPartId=-1|Color=8388608|FontID=1|IsHidden=T|Text=2D|Name=Available Preview Images
|RECORD=45|OwnerIndex=1107|IndexInSheet=-1|Description=Chip Resistor, 2-Leads, Body 1.00x0.50mm, IPC Low Density|UseComponentLibrary=T|ModelName=RESC1005X40X25ML10T10|ModelType=PCBLIB|DatafileCount=1|ModelDatafileEntity0=RESC1005X40X25ML10T10|ModelDatafileKind0=PCBLib|DatalinksLocked=T|DatabaseDatalinksLocked=T
|RECORD=46|OwnerIndex=1116
|RECORD=48|OwnerIndex=1116
|RECORD=41|OwnerIndex=1118|IndexInSheet=-1|OwnerPartId=-1|Color=8388608|FontID=1|IsHidden=T|Text=2D|Name=Available Preview Images
|RECORD=1|LibReference=RES|PartCount=2|DisplayModeCount=2|IndexInSheet=179|OwnerPartId=-1|Location.X=310|Location.Y=700|Orientation=3|CurrentPartId=1|SourceLibraryName=Altium Content Vault|TargetFileName=*|AreaColor=11599871|Color=128|PartIDLocked=F|DesignItemId=CMP-2002-05217-1|AllPinCount=2
|RECORD=2|OwnerIndex=1120|OwnerPartId=1|OwnerPartDisplayMode=1|FormalType=1|Electrical=4|PinConglomerate=35|PinLength=10|Location.X=300|Location.Y=680|Name=2|Designator=2|PinPropagationDelay=0.000000E+000
|RECORD=2|OwnerIndex=1120|OwnerPartId=1|OwnerPartDisplayMode=1|FormalType=1|Electrical=4|PinConglomerate=33|PinLength=10|Location.X=300|Location.Y=700|Name=1|Designator=1|PinPropagationDelay=0.000000E+000
|RECORD=14|OwnerIndex=1120|IsNotAccesible=T|IndexInSheet=2|OwnerPartId=1|OwnerPartDisplayMode=1|Location.X=296|Location.Y=680|Corner.X=304|Corner.Y=700|LineWidth=1|Color=16711680|AreaColor=11599871
|RECORD=2|OwnerIndex=1120|OwnerPartId=1|FormalType=1|Electrical=4|PinConglomerate=35|PinLength=10|Location.X=300|Location.Y=680|Name=2|Designator=2|PinPropagationDelay=0.000000E+000
|RECORD=2|OwnerIndex=1120|OwnerPartId=1|FormalType=1|Electrical=4|PinConglomerate=33|PinLength=10|Location.X=300|Location.Y=700|Name=1|Designator=1|PinPropagationDelay=0.000000E+000
|RECORD=6|OwnerIndex=1120|IsNotAccesible=T|IndexInSheet=5|OwnerPartId=1|LineWidth=1|Color=16711680|LocationCount=10|X1=300|Y1=680|X2=300|Y2=684|X3=298|Y3=685|X4=302|Y4=687|X5=298|Y5=689|X6=302|Y6=691|X7=298|Y7=693|X8=302|Y8=695|X9=300|Y9=696|X10=300|Y10=700
|RECORD=41|OwnerIndex=1120|IndexInSheet=6|OwnerPartId=-1|Location.X=297|Location.Y=712|Color=8388608|FontID=1|IsHidden=T|Text=Bourns|Name=Manufacturer
|RECORD=41|OwnerIndex=1120|IndexInSheet=7|OwnerPartId=-1|Location.X=297|Location.Y=712|Color=8388608|FontID=1|IsHidden=T|Text=CR0402-FX-4701GLF|Name=Part Number
|RECORD=34|OwnerIndex=1120|IndexInSheet=-1|OwnerPartId=-1|Location.X=300|Location.Y=670|Orientation=1|Color=8388608|FontID=2|Text=R30|Name=Designator|ReadOnlyState=1
|RECORD=41|OwnerIndex=1120|IndexInSheet=-1|OwnerPartId=-1|Location.X=310|Location.Y=660|Orientation=1|Color=8388608|FontID=2|Text=4.7K_1%_0402|Name=Comment
|RECORD=44|OwnerIndex=1120
|RECORD=45|OwnerIndex=1135|IndexInSheet=-1|Description=Chip Resistor, 2-Leads, Body 1.00x0.50mm, IPC Medium Density|UseComponentLibrary=T|ModelName=RESC1005X40X25NL10T10|ModelType=PCBLIB|DatafileCount=1|ModelDatafileEntity0=RESC1005X40X25NL10T10|ModelDatafileKind0=PCBLib|IsCurrent=T|DatalinksLocked=T|DatabaseDatalinksLocked=T
|RECORD=46|OwnerIndex=1136
|RECORD=48|OwnerIndex=1136
|RECORD=41|OwnerIndex=1138|IndexInSheet=-1|OwnerPartId=-1|Color=8388608|FontID=1|IsHidden=T|Text=2D|Name=Available Preview Images
|RECORD=45|OwnerIndex=1135|IndexInSheet=-1|Description=Chip Resistor, 2-Leads, Body 1.00x0.50mm, IPC High Density|UseComponentLibrary=T|ModelName=RESC1005X40X25LL10T10|ModelType=PCBLIB|DatafileCount=1|ModelDatafileEntity0=RESC1005X40X25LL10T10|ModelDatafileKind0=PCBLib|DatalinksLocked=T|DatabaseDatalinksLocked=T
|RECORD=46|OwnerIndex=1140
|RECORD=48|OwnerIndex=1140
|RECORD=41|OwnerIndex=1142|IndexInSheet=-1|OwnerPartId=-1|Color=8388608|FontID=1|IsHidden=T|Text=2D|Name=Available Preview Images
|RECORD=45|OwnerIndex=1135|IndexInSheet=-1|Description=Chip Resistor, 2-Leads, Body 1.00x0.50mm, IPC Low Density|UseComponentLibrary=T|ModelName=RESC1005X40X25ML10T10|ModelType=PCBLIB|DatafileCount=1|ModelDatafileEntity0=RESC1005X40X25ML10T10|ModelDatafileKind0=PCBLib|DatalinksLocked=T|DatabaseDatalinksLocked=T
|RECORD=46|OwnerIndex=1144
|RECORD=48|OwnerIndex=1144
|RECORD=41|OwnerIndex=1146|IndexInSheet=-1|OwnerPartId=-1|Color=8388608|FontID=1|IsHidden=T|Text=2D|Name=Available Preview Images
|RECORD=27|IndexInSheet=180|OwnerPartId=-1|LineWidth=1|Color=8388608|LocationCount=3|X1=1154|Y1=917|X2=1060|Y2=917|X3=964|Y3=917
|RECORD=27|IndexInSheet=181|OwnerPartId=-1|LineWidth=1|Color=8388608|LocationCount=2|X1=1060|Y1=917|X2=1060|Y2=1000
|RECORD=27|IndexInSheet=182|OwnerPartId=-1|LineWidth=1|Color=8388608|LocationCount=5|X1=1154|Y1=972|X2=1154|Y2=970|X3=1030|Y3=970|X4=964|Y4=970|X5=964|Y5=972
|RECORD=1|LibReference=RES|PartCount=2|DisplayModeCount=2|IndexInSheet=183|OwnerPartId=-1|Location.X=1040|Location.Y=1025|Orientation=3|CurrentPartId=1|SourceLibraryName=Altium Content Vault|TargetFileName=*|AreaColor=11599871|Color=128|PartIDLocked=F|DesignItemId=CMP-2002-05217-1|AllPinCount=2
|RECORD=2|OwnerIndex=1151|OwnerPartId=1|OwnerPartDisplayMode=1|FormalType=1|Electrical=4|PinConglomerate=35|PinLength=10|Location.X=1030|Location.Y=1005|Name=2|Designator=2|PinPropagationDelay=0.000000E+000
|RECORD=2|OwnerIndex=1151|OwnerPartId=1|OwnerPartDisplayMode=1|FormalType=1|Electrical=4|PinConglomerate=33|PinLength=10|Location.X=1030|Location.Y=1025|Name=1|Designator=1|PinPropagationDelay=0.000000E+000
|RECORD=14|OwnerIndex=1151|IsNotAccesible=T|IndexInSheet=2|OwnerPartId=1|OwnerPartDisplayMode=1|Location.X=1026|Location.Y=1005|Corner.X=1034|Corner.Y=1025|LineWidth=1|Color=16711680|AreaColor=11599871
|RECORD=2|OwnerIndex=1151|OwnerPartId=1|FormalType=1|Electrical=4|PinConglomerate=35|PinLength=10|Location.X=1030|Location.Y=1005|Name=2|Designator=2|PinPropagationDelay=0.000000E+000
|RECORD=2|OwnerIndex=1151|OwnerPartId=1|FormalType=1|Electrical=4|PinConglomerate=33|PinLength=10|Location.X=1030|Location.Y=1025|Name=1|Designator=1|PinPropagationDelay=0.000000E+000
|RECORD=6|OwnerIndex=1151|IsNotAccesible=T|IndexInSheet=5|OwnerPartId=1|LineWidth=1|Color=16711680|LocationCount=10|X1=1030|Y1=1005|X2=1030|Y2=1009|X3=1028|Y3=1010|X4=1032|Y4=1012|X5=1028|Y5=1014|X6=1032|Y6=1016|X7=1028|Y7=1018|X8=1032|Y8=1020|X9=1030|Y9=1021|X10=1030|Y10=1025
|RECORD=41|OwnerIndex=1151|IndexInSheet=6|OwnerPartId=-1|Location.X=1027|Location.Y=1037|Color=8388608|FontID=1|IsHidden=T|Text=Bourns|Name=Manufacturer
|RECORD=41|OwnerIndex=1151|IndexInSheet=7|OwnerPartId=-1|Location.X=1027|Location.Y=1037|Color=8388608|FontID=1|IsHidden=T|Text=CR0402-FX-4701GLF|Name=Part Number
|RECORD=34|OwnerIndex=1151|IndexInSheet=-1|OwnerPartId=-1|Location.X=1030|Location.Y=995|Orientation=1|Color=8388608|FontID=2|Text=R17|Name=Designator|ReadOnlyState=1
|RECORD=41|OwnerIndex=1151|IndexInSheet=-1|OwnerPartId=-1|Location.X=1040|Location.Y=985|Orientation=1|Color=8388608|FontID=2|Text=4.7K_1%_0402|Name=Comment
|RECORD=44|OwnerIndex=1151
|RECORD=45|OwnerIndex=1166|IndexInSheet=-1|Description=Chip Resistor, 2-Leads, Body 1.00x0.50mm, IPC Medium Density|UseComponentLibrary=T|ModelName=RESC1005X40X25NL10T10|ModelType=PCBLIB|DatafileCount=1|ModelDatafileEntity0=RESC1005X40X25NL10T10|ModelDatafileKind0=PCBLib|IsCurrent=T|DatalinksLocked=T|DatabaseDatalinksLocked=T
|RECORD=46|OwnerIndex=1167
|RECORD=48|OwnerIndex=1167
|RECORD=41|OwnerIndex=1169|IndexInSheet=-1|OwnerPartId=-1|Color=8388608|FontID=1|IsHidden=T|Text=2D|Name=Available Preview Images
|RECORD=45|OwnerIndex=1166|IndexInSheet=-1|Description=Chip Resistor, 2-Leads, Body 1.00x0.50mm, IPC High Density|UseComponentLibrary=T|ModelName=RESC1005X40X25LL10T10|ModelType=PCBLIB|DatafileCount=1|ModelDatafileEntity0=RESC1005X40X25LL10T10|ModelDatafileKind0=PCBLib|DatalinksLocked=T|DatabaseDatalinksLocked=T
|RECORD=46|OwnerIndex=1171
|RECORD=48|OwnerIndex=1171
|RECORD=41|OwnerIndex=1173|IndexInSheet=-1|OwnerPartId=-1|Color=8388608|FontID=1|IsHidden=T|Text=2D|Name=Available Preview Images
|RECORD=45|OwnerIndex=1166|IndexInSheet=-1|Description=Chip Resistor, 2-Leads, Body 1.00x0.50mm, IPC Low Density|UseComponentLibrary=T|ModelName=RESC1005X40X25ML10T10|ModelType=PCBLIB|DatafileCount=1|ModelDatafileEntity0=RESC1005X40X25ML10T10|ModelDatafileKind0=PCBLib|DatalinksLocked=T|DatabaseDatalinksLocked=T
|RECORD=46|OwnerIndex=1175
|RECORD=48|OwnerIndex=1175
|RECORD=41|OwnerIndex=1177|IndexInSheet=-1|OwnerPartId=-1|Color=8388608|FontID=1|IsHidden=T|Text=2D|Name=Available Preview Images
|RECORD=1|LibReference=RES|PartCount=2|DisplayModeCount=2|IndexInSheet=184|OwnerPartId=-1|Location.X=1070|Location.Y=1030|Orientation=3|CurrentPartId=1|SourceLibraryName=Altium Content Vault|TargetFileName=*|AreaColor=11599871|Color=128|PartIDLocked=F|DesignItemId=CMP-2002-05217-1|AllPinCount=2
|RECORD=2|OwnerIndex=1179|OwnerPartId=1|OwnerPartDisplayMode=1|FormalType=1|Electrical=4|PinConglomerate=35|PinLength=10|Location.X=1060|Location.Y=1010|Name=2|Designator=2|PinPropagationDelay=0.000000E+000
|RECORD=2|OwnerIndex=1179|OwnerPartId=1|OwnerPartDisplayMode=1|FormalType=1|Electrical=4|PinConglomerate=33|PinLength=10|Location.X=1060|Location.Y=1030|Name=1|Designator=1|PinPropagationDelay=0.000000E+000
|RECORD=14|OwnerIndex=1179|IsNotAccesible=T|IndexInSheet=2|OwnerPartId=1|OwnerPartDisplayMode=1|Location.X=1056|Location.Y=1010|Corner.X=1064|Corner.Y=1030|LineWidth=1|Color=16711680|AreaColor=11599871
|RECORD=2|OwnerIndex=1179|OwnerPartId=1|FormalType=1|Electrical=4|PinConglomerate=35|PinLength=10|Location.X=1060|Location.Y=1010|Name=2|Designator=2|PinPropagationDelay=0.000000E+000
|RECORD=2|OwnerIndex=1179|OwnerPartId=1|FormalType=1|Electrical=4|PinConglomerate=33|PinLength=10|Location.X=1060|Location.Y=1030|Name=1|Designator=1|PinPropagationDelay=0.000000E+000
|RECORD=6|OwnerIndex=1179|IsNotAccesible=T|IndexInSheet=5|OwnerPartId=1|LineWidth=1|Color=16711680|LocationCount=10|X1=1060|Y1=1010|X2=1060|Y2=1014|X3=1058|Y3=1015|X4=1062|Y4=1017|X5=1058|Y5=1019|X6=1062|Y6=1021|X7=1058|Y7=1023|X8=1062|Y8=1025|X9=1060|Y9=1026|X10=1060|Y10=1030
|RECORD=41|OwnerIndex=1179|IndexInSheet=6|OwnerPartId=-1|Location.X=1057|Location.Y=1042|Color=8388608|FontID=1|IsHidden=T|Text=Bourns|Name=Manufacturer
|RECORD=41|OwnerIndex=1179|IndexInSheet=7|OwnerPartId=-1|Location.X=1057|Location.Y=1042|Color=8388608|FontID=1|IsHidden=T|Text=CR0402-FX-4701GLF|Name=Part Number
|RECORD=34|OwnerIndex=1179|IndexInSheet=-1|OwnerPartId=-1|Location.X=1060|Location.Y=1000|Orientation=1|Color=8388608|FontID=2|Text=R16|Name=Designator|ReadOnlyState=1
|RECORD=41|OwnerIndex=1179|IndexInSheet=-1|OwnerPartId=-1|Location.X=1070|Location.Y=990|Orientation=1|Color=8388608|FontID=2|Text=4.7K_1%_0402|Name=Comment
|RECORD=44|OwnerIndex=1179
|RECORD=45|OwnerIndex=1194|IndexInSheet=-1|Description=Chip Resistor, 2-Leads, Body 1.00x0.50mm, IPC Medium Density|UseComponentLibrary=T|ModelName=RESC1005X40X25NL10T10|ModelType=PCBLIB|DatafileCount=1|ModelDatafileEntity0=RESC1005X40X25NL10T10|ModelDatafileKind0=PCBLib|IsCurrent=T|DatalinksLocked=T|DatabaseDatalinksLocked=T
|RECORD=46|OwnerIndex=1195
|RECORD=48|OwnerIndex=1195
|RECORD=41|OwnerIndex=1197|IndexInSheet=-1|OwnerPartId=-1|Color=8388608|FontID=1|IsHidden=T|Text=2D|Name=Available Preview Images
|RECORD=45|OwnerIndex=1194|IndexInSheet=-1|Description=Chip Resistor, 2-Leads, Body 1.00x0.50mm, IPC High Density|UseComponentLibrary=T|ModelName=RESC1005X40X25LL10T10|ModelType=PCBLIB|DatafileCount=1|ModelDatafileEntity0=RESC1005X40X25LL10T10|ModelDatafileKind0=PCBLib|DatalinksLocked=T|DatabaseDatalinksLocked=T
|RECORD=46|OwnerIndex=1199
|RECORD=48|OwnerIndex=1199
|RECORD=41|OwnerIndex=1201|IndexInSheet=-1|OwnerPartId=-1|Color=8388608|FontID=1|IsHidden=T|Text=2D|Name=Available Preview Images
|RECORD=45|OwnerIndex=1194|IndexInSheet=-1|Description=Chip Resistor, 2-Leads, Body 1.00x0.50mm, IPC Low Density|UseComponentLibrary=T|ModelName=RESC1005X40X25ML10T10|ModelType=PCBLIB|DatafileCount=1|ModelDatafileEntity0=RESC1005X40X25ML10T10|ModelDatafileKind0=PCBLib|DatalinksLocked=T|DatabaseDatalinksLocked=T
|RECORD=46|OwnerIndex=1203
|RECORD=48|OwnerIndex=1203
|RECORD=41|OwnerIndex=1205|IndexInSheet=-1|OwnerPartId=-1|Color=8388608|FontID=1|IsHidden=T|Text=2D|Name=Available Preview Images
|RECORD=27|IndexInSheet=185|OwnerPartId=-1|LineWidth=1|Color=8388608|LocationCount=2|X1=1030|Y1=1035|X2=1030|Y2=1060
|RECORD=27|IndexInSheet=186|OwnerPartId=-1|LineWidth=1|Color=8388608|LocationCount=2|X1=1060|Y1=1040|X2=1060|Y2=1060
|RECORD=27|IndexInSheet=187|OwnerPartId=-1|LineWidth=1|Color=8388608|LocationCount=2|X1=1030|Y1=720|X2=1030|Y2=710
|RECORD=27|IndexInSheet=188|OwnerPartId=-1|LineWidth=1|Color=8388608|LocationCount=2|X1=1030|Y1=670|X2=1030|Y2=642
|RECORD=27|IndexInSheet=189|OwnerPartId=-1|LineWidth=1|Color=8388608|LocationCount=2|X1=1060|Y1=670|X2=1060|Y2=587
|RECORD=27|IndexInSheet=190|OwnerPartId=-1|LineWidth=1|Color=8388608|LocationCount=2|X1=1060|Y1=720|X2=1060|Y2=710
|RECORD=1|LibReference=RES|PartCount=2|DisplayModeCount=2|IndexInSheet=191|OwnerPartId=-1|Location.X=1040|Location.Y=700|Orientation=3|CurrentPartId=1|SourceLibraryName=Altium Content Vault|TargetFileName=*|AreaColor=11599871|Color=128|PartIDLocked=F|DesignItemId=CMP-2002-05217-1|AllPinCount=2
|RECORD=2|OwnerIndex=1213|OwnerPartId=1|OwnerPartDisplayMode=1|FormalType=1|Electrical=4|PinConglomerate=35|PinLength=10|Location.X=1030|Location.Y=680|Name=2|Designator=2|PinPropagationDelay=0.000000E+000
|RECORD=2|OwnerIndex=1213|OwnerPartId=1|OwnerPartDisplayMode=1|FormalType=1|Electrical=4|PinConglomerate=33|PinLength=10|Location.X=1030|Location.Y=700|Name=1|Designator=1|PinPropagationDelay=0.000000E+000
|RECORD=14|OwnerIndex=1213|IsNotAccesible=T|IndexInSheet=2|OwnerPartId=1|OwnerPartDisplayMode=1|Location.X=1026|Location.Y=680|Corner.X=1034|Corner.Y=700|LineWidth=1|Color=16711680|AreaColor=11599871
|RECORD=2|OwnerIndex=1213|OwnerPartId=1|FormalType=1|Electrical=4|PinConglomerate=35|PinLength=10|Location.X=1030|Location.Y=680|Name=2|Designator=2|PinPropagationDelay=0.000000E+000
|RECORD=2|OwnerIndex=1213|OwnerPartId=1|FormalType=1|Electrical=4|PinConglomerate=33|PinLength=10|Location.X=1030|Location.Y=700|Name=1|Designator=1|PinPropagationDelay=0.000000E+000
|RECORD=6|OwnerIndex=1213|IsNotAccesible=T|IndexInSheet=5|OwnerPartId=1|LineWidth=1|Color=16711680|LocationCount=10|X1=1030|Y1=680|X2=1030|Y2=684|X3=1028|Y3=685|X4=1032|Y4=687|X5=1028|Y5=689|X6=1032|Y6=691|X7=1028|Y7=693|X8=1032|Y8=695|X9=1030|Y9=696|X10=1030|Y10=700
|RECORD=41|OwnerIndex=1213|IndexInSheet=6|OwnerPartId=-1|Location.X=1027|Location.Y=712|Color=8388608|FontID=1|IsHidden=T|Text=Bourns|Name=Manufacturer
|RECORD=41|OwnerIndex=1213|IndexInSheet=7|OwnerPartId=-1|Location.X=1027|Location.Y=712|Color=8388608|FontID=1|IsHidden=T|Text=CR0402-FX-4701GLF|Name=Part Number
|RECORD=34|OwnerIndex=1213|IndexInSheet=-1|OwnerPartId=-1|Location.X=1030|Location.Y=670|Orientation=1|Color=8388608|FontID=2|Text=R31|Name=Designator|ReadOnlyState=1
|RECORD=41|OwnerIndex=1213|IndexInSheet=-1|OwnerPartId=-1|Location.X=1040|Location.Y=660|Orientation=1|Color=8388608|FontID=2|Text=4.7K_1%_0402|Name=Comment
|RECORD=44|OwnerIndex=1213
|RECORD=45|OwnerIndex=1228|IndexInSheet=-1|Description=Chip Resistor, 2-Leads, Body 1.00x0.50mm, IPC Medium Density|UseComponentLibrary=T|ModelName=RESC1005X40X25NL10T10|ModelType=PCBLIB|DatafileCount=1|ModelDatafileEntity0=RESC1005X40X25NL10T10|ModelDatafileKind0=PCBLib|IsCurrent=T|DatalinksLocked=T|DatabaseDatalinksLocked=T
|RECORD=46|OwnerIndex=1229
|RECORD=48|OwnerIndex=1229
|RECORD=41|OwnerIndex=1231|IndexInSheet=-1|OwnerPartId=-1|Color=8388608|FontID=1|IsHidden=T|Text=2D|Name=Available Preview Images
|RECORD=45|OwnerIndex=1228|IndexInSheet=-1|Description=Chip Resistor, 2-Leads, Body 1.00x0.50mm, IPC High Density|UseComponentLibrary=T|ModelName=RESC1005X40X25LL10T10|ModelType=PCBLIB|DatafileCount=1|ModelDatafileEntity0=RESC1005X40X25LL10T10|ModelDatafileKind0=PCBLib|DatalinksLocked=T|DatabaseDatalinksLocked=T
|RECORD=46|OwnerIndex=1233
|RECORD=48|OwnerIndex=1233
|RECORD=41|OwnerIndex=1235|IndexInSheet=-1|OwnerPartId=-1|Color=8388608|FontID=1|IsHidden=T|Text=2D|Name=Available Preview Images
|RECORD=45|OwnerIndex=1228|IndexInSheet=-1|Description=Chip Resistor, 2-Leads, Body 1.00x0.50mm, IPC Low Density|UseComponentLibrary=T|ModelName=RESC1005X40X25ML10T10|ModelType=PCBLIB|DatafileCount=1|ModelDatafileEntity0=RESC1005X40X25ML10T10|ModelDatafileKind0=PCBLib|DatalinksLocked=T|DatabaseDatalinksLocked=T
|RECORD=46|OwnerIndex=1237
|RECORD=48|OwnerIndex=1237
|RECORD=41|OwnerIndex=1239|IndexInSheet=-1|OwnerPartId=-1|Color=8388608|FontID=1|IsHidden=T|Text=2D|Name=Available Preview Images
|RECORD=1|LibReference=RES|PartCount=2|DisplayModeCount=2|IndexInSheet=192|OwnerPartId=-1|Location.X=1070|Location.Y=700|Orientation=3|CurrentPartId=1|SourceLibraryName=Altium Content Vault|TargetFileName=*|AreaColor=11599871|Color=128|PartIDLocked=F|DesignItemId=CMP-2002-05217-1|AllPinCount=2
|RECORD=2|OwnerIndex=1241|OwnerPartId=1|OwnerPartDisplayMode=1|FormalType=1|Electrical=4|PinConglomerate=35|PinLength=10|Location.X=1060|Location.Y=680|Name=2|Designator=2|PinPropagationDelay=0.000000E+000
|RECORD=2|OwnerIndex=1241|OwnerPartId=1|OwnerPartDisplayMode=1|FormalType=1|Electrical=4|PinConglomerate=33|PinLength=10|Location.X=1060|Location.Y=700|Name=1|Designator=1|PinPropagationDelay=0.000000E+000
|RECORD=14|OwnerIndex=1241|IsNotAccesible=T|IndexInSheet=2|OwnerPartId=1|OwnerPartDisplayMode=1|Location.X=1056|Location.Y=680|Corner.X=1064|Corner.Y=700|LineWidth=1|Color=16711680|AreaColor=11599871
|RECORD=2|OwnerIndex=1241|OwnerPartId=1|FormalType=1|Electrical=4|PinConglomerate=35|PinLength=10|Location.X=1060|Location.Y=680|Name=2|Designator=2|PinPropagationDelay=0.000000E+000
|RECORD=2|OwnerIndex=1241|OwnerPartId=1|FormalType=1|Electrical=4|PinConglomerate=33|PinLength=10|Location.X=1060|Location.Y=700|Name=1|Designator=1|PinPropagationDelay=0.000000E+000
|RECORD=6|OwnerIndex=1241|IsNotAccesible=T|IndexInSheet=5|OwnerPartId=1|LineWidth=1|Color=16711680|LocationCount=10|X1=1060|Y1=680|X2=1060|Y2=684|X3=1058|Y3=685|X4=1062|Y4=687|X5=1058|Y5=689|X6=1062|Y6=691|X7=1058|Y7=693|X8=1062|Y8=695|X9=1060|Y9=696|X10=1060|Y10=700
|RECORD=41|OwnerIndex=1241|IndexInSheet=6|OwnerPartId=-1|Location.X=1057|Location.Y=712|Color=8388608|FontID=1|IsHidden=T|Text=Bourns|Name=Manufacturer
|RECORD=41|OwnerIndex=1241|IndexInSheet=7|OwnerPartId=-1|Location.X=1057|Location.Y=712|Color=8388608|FontID=1|IsHidden=T|Text=CR0402-FX-4701GLF|Name=Part Number
|RECORD=34|OwnerIndex=1241|IndexInSheet=-1|OwnerPartId=-1|Location.X=1060|Location.Y=670|Orientation=1|Color=8388608|FontID=2|Text=R32|Name=Designator|ReadOnlyState=1
|RECORD=41|OwnerIndex=1241|IndexInSheet=-1|OwnerPartId=-1|Location.X=1070|Location.Y=660|Orientation=1|Color=8388608|FontID=2|Text=4.7K_1%_0402|Name=Comment
|RECORD=44|OwnerIndex=1241
|RECORD=45|OwnerIndex=1256|IndexInSheet=-1|Description=Chip Resistor, 2-Leads, Body 1.00x0.50mm, IPC Medium Density|UseComponentLibrary=T|ModelName=RESC1005X40X25NL10T10|ModelType=PCBLIB|DatafileCount=1|ModelDatafileEntity0=RESC1005X40X25NL10T10|ModelDatafileKind0=PCBLib|IsCurrent=T|DatalinksLocked=T|DatabaseDatalinksLocked=T
|RECORD=46|OwnerIndex=1257
|RECORD=48|OwnerIndex=1257
|RECORD=41|OwnerIndex=1259|IndexInSheet=-1|OwnerPartId=-1|Color=8388608|FontID=1|IsHidden=T|Text=2D|Name=Available Preview Images
|RECORD=45|OwnerIndex=1256|IndexInSheet=-1|Description=Chip Resistor, 2-Leads, Body 1.00x0.50mm, IPC High Density|UseComponentLibrary=T|ModelName=RESC1005X40X25LL10T10|ModelType=PCBLIB|DatafileCount=1|ModelDatafileEntity0=RESC1005X40X25LL10T10|ModelDatafileKind0=PCBLib|DatalinksLocked=T|DatabaseDatalinksLocked=T
|RECORD=46|OwnerIndex=1261
|RECORD=48|OwnerIndex=1261
|RECORD=41|OwnerIndex=1263|IndexInSheet=-1|OwnerPartId=-1|Color=8388608|FontID=1|IsHidden=T|Text=2D|Name=Available Preview Images
|RECORD=45|OwnerIndex=1256|IndexInSheet=-1|Description=Chip Resistor, 2-Leads, Body 1.00x0.50mm, IPC Low Density|UseComponentLibrary=T|ModelName=RESC1005X40X25ML10T10|ModelType=PCBLIB|DatafileCount=1|ModelDatafileEntity0=RESC1005X40X25ML10T10|ModelDatafileKind0=PCBLib|DatalinksLocked=T|DatabaseDatalinksLocked=T
|RECORD=46|OwnerIndex=1265
|RECORD=48|OwnerIndex=1265
|RECORD=41|OwnerIndex=1267|IndexInSheet=-1|OwnerPartId=-1|Color=8388608|FontID=1|IsHidden=T|Text=2D|Name=Available Preview Images
|RECORD=1|LibReference=b4654b650e69147ec39a6b967a45e02|ComponentDescription=General Purpose Ceramic Capacitor, 0402, 100nF, 10%, X7R, 15%, 25V|PartCount=2|DisplayModeCount=1|IndexInSheet=193|OwnerPartId=-1|Location.X=1094|Location.Y=527|CurrentPartId=1|LibraryPath=*|SourceLibraryName=Altium Content Vault|TargetFileName=*|AreaColor=11599871|Color=128|PartIDLocked=T|DesignItemId=CMP-2008-02519-2|AllPinCount=2
|RECORD=2|OwnerIndex=1269|OwnerPartId=1|Electrical=4|PinConglomerate=49|PinLength=7|Location.X=1094|Location.Y=520|Name=1|Designator=1|PinPropagationDelay=0.000000E+000
|RECORD=2|OwnerIndex=1269|OwnerPartId=1|Electrical=4|PinConglomerate=51|PinLength=6|Location.X=1094|Location.Y=513|Name=2|Designator=2|PinPropagationDelay=0.000000E+000
|RECORD=13|OwnerIndex=1269|IsNotAccesible=T|IndexInSheet=2|OwnerPartId=1|Location.X=1104|Location.Y=520|Corner.X=1084|Corner.Y=520|LineWidth=1|Color=16711680
|RECORD=13|OwnerIndex=1269|IsNotAccesible=T|IndexInSheet=3|OwnerPartId=1|Location.X=1104|Location.Y=514|Corner.X=1084|Corner.Y=514|LineWidth=1|Color=16711680
|RECORD=13|OwnerIndex=1269|IsNotAccesible=T|IndexInSheet=4|OwnerPartId=1|Location.X=1094|Location.Y=520|Corner.X=1094|Corner.Y=523|LineWidth=1|Color=16711680
|RECORD=13|OwnerIndex=1269|IsNotAccesible=T|IndexInSheet=5|OwnerPartId=1|Location.X=1094|Location.Y=513|Corner.X=1094|Corner.Y=512|LineWidth=1|Color=16711680
|RECORD=41|OwnerIndex=1269|IndexInSheet=6|OwnerPartId=-1|Location.X=1083|Location.Y=529|Color=8388608|FontID=1|IsHidden=T|Text=1|Name=Package Quantity
|RECORD=41|OwnerIndex=1269|IndexInSheet=7|OwnerPartId=-1|Location.X=1083|Location.Y=529|Color=8388608|FontID=1|IsHidden=T|Text=100nF|Name=Capacitance
|RECORD=41|OwnerIndex=1269|IndexInSheet=8|OwnerPartId=-1|Location.X=1083|Location.Y=529|Color=8388608|FontID=1|IsHidden=T|Text=-55°C|Name=Min Operating Temperature
|RECORD=41|OwnerIndex=1269|IndexInSheet=9|OwnerPartId=-1|Location.X=1083|Location.Y=529|Color=8388608|FontID=1|IsHidden=T|Text=25V|Name=Voltage
|RECORD=41|OwnerIndex=1269|IndexInSheet=10|OwnerPartId=-1|Location.X=1083|Location.Y=529|Color=8388608|FontID=1|IsHidden=T|Text=25V|Name=Voltage Rating
|RECORD=41|OwnerIndex=1269|IndexInSheet=11|OwnerPartId=-1|Location.X=1083|Location.Y=529|Color=8388608|FontID=1|IsHidden=T|Text=Flat|Name=Construction
|RECORD=41|OwnerIndex=1269|IndexInSheet=12|OwnerPartId=-1|Location.X=1083|Location.Y=529|Color=8388608|FontID=1|IsHidden=T|Text=125°C|Name=Max Operating Temperature
|RECORD=41|OwnerIndex=1269|IndexInSheet=13|OwnerPartId=-1|Location.X=1083|Location.Y=529|Color=8388608|FontID=1|IsHidden=T|Text=No|Name=Radiation Hardening
|RECORD=41|OwnerIndex=1269|IndexInSheet=14|OwnerPartId=-1|Location.X=1083|Location.Y=529|Color=8388608|FontID=1|IsHidden=T|Text=0.5mm|Name=Depth
|RECORD=41|OwnerIndex=1269|IndexInSheet=15|OwnerPartId=-1|Location.X=1083|Location.Y=529|Color=8388608|FontID=1|IsHidden=T|Text=0.022inch|Name=Thickness
|RECORD=41|OwnerIndex=1269|IndexInSheet=16|OwnerPartId=-1|Location.X=1083|Location.Y=529|Color=8388608|FontID=1|IsHidden=T|Text=25V|Name=Voltage Rating (DC)
|RECORD=41|OwnerIndex=1269|IndexInSheet=17|OwnerPartId=-1|Location.X=1083|Location.Y=529|Color=8388608|FontID=1|IsHidden=T|Text=2|Name=Number of Pins
|RECORD=41|OwnerIndex=1269|IndexInSheet=18|OwnerPartId=-1|Location.X=1083|Location.Y=529|Color=8388608|FontID=1|IsHidden=T|Text=Lead Free|Name=Lead Free
|RECORD=41|OwnerIndex=1269|IndexInSheet=19|OwnerPartId=-1|Location.X=1083|Location.Y=529|Color=8388608|FontID=1|IsHidden=T|Text=-|Name=Series
|RECORD=41|OwnerIndex=1269|IndexInSheet=20|OwnerPartId=-1|Location.X=1083|Location.Y=529|Color=8388608|FontID=1|IsHidden=T|Text=No SVHC|Name=REACH SVHC
|RECORD=41|OwnerIndex=1269|IndexInSheet=21|OwnerPartId=-1|Location.X=1083|Location.Y=529|Color=8388608|FontID=1|IsHidden=T|Text=1mm|Name=Length
|RECORD=41|OwnerIndex=1269|IndexInSheet=22|OwnerPartId=-1|Location.X=1083|Location.Y=529|Color=8388608|FontID=1|IsHidden=T|Text=X7R|Name=Dielectric
|RECORD=41|OwnerIndex=1269|IndexInSheet=23|OwnerPartId=-1|Location.X=1083|Location.Y=529|Color=8388608|FontID=1|IsHidden=T|Text=Yes|Name=RoHS Compliant
|RECORD=41|OwnerIndex=1269|IndexInSheet=24|OwnerPartId=-1|Location.X=1083|Location.Y=529|Color=8388608|FontID=1|IsHidden=T|Text=Surface Mount|Name=Mount
|RECORD=41|OwnerIndex=1269|IndexInSheet=25|OwnerPartId=-1|Location.X=1083|Location.Y=529|Color=8388608|FontID=1|IsHidden=T|Text=Tape and Reel|Name=Packaging
|RECORD=41|OwnerIndex=1269|IndexInSheet=26|OwnerPartId=-1|Location.X=1083|Location.Y=529|Color=8388608|FontID=1|IsHidden=T|Text=0402|Name=Case/Package
|RECORD=41|OwnerIndex=1269|IndexInSheet=27|OwnerPartId=-1|Location.X=1083|Location.Y=529|Color=8388608|FontID=1|IsHidden=T|Text=0402|Name=Case Code (Imperial)
|RECORD=41|OwnerIndex=1269|IndexInSheet=28|OwnerPartId=-1|Location.X=1083|Location.Y=529|Color=8388608|FontID=1|IsHidden=T|Text=SMD/SMT|Name=Termination
|RECORD=41|OwnerIndex=1269|IndexInSheet=29|OwnerPartId=-1|Location.X=1083|Location.Y=529|Color=8388608|FontID=1|IsHidden=T|Text=0.02inch|Name=Width
|RECORD=41|OwnerIndex=1269|IndexInSheet=30|OwnerPartId=-1|Location.X=1083|Location.Y=529|Color=8388608|FontID=1|IsHidden=T|Text=1005|Name=Case Code (Metric)
|RECORD=41|OwnerIndex=1269|IndexInSheet=31|OwnerPartId=-1|Location.X=1083|Location.Y=529|Color=8388608|FontID=1|IsHidden=T|Text=10%|Name=Tolerance
|RECORD=34|OwnerIndex=1269|IndexInSheet=-1|OwnerPartId=-1|Location.X=1084|Location.Y=507|Orientation=1|Color=8388608|FontID=2|Text=C28|Name=Designator|ReadOnlyState=1
|RECORD=41|OwnerIndex=1269|IndexInSheet=-1|OwnerPartId=1|Location.X=1114|Location.Y=492|Orientation=1|Color=8388608|FontID=2|Text=0.1uF_25V_0402|Name=Comment
|RECORD=44|OwnerIndex=1269
|RECORD=45|OwnerIndex=1306|IndexInSheet=-1|UseComponentLibrary=T|ModelName=FP-0402-L_1_0_1-W_0_5_0_1-IPC_C|ModelType=PCBLIB|DatafileCount=1|ModelDatafileEntity0=FP-0402-L_1_0_1-W_0_5_0_1-IPC_C|ModelDatafileKind0=PCBLib|IsCurrent=T|DatalinksLocked=T|DatabaseDatalinksLocked=T
|RECORD=46|OwnerIndex=1307
|RECORD=48|OwnerIndex=1307
|RECORD=45|OwnerIndex=1306|IndexInSheet=-1|UseComponentLibrary=T|ModelName=FP-0402-L_1_0_1-W_0_5_0_1-IPC_B|ModelType=PCBLIB|DatafileCount=1|ModelDatafileEntity0=FP-0402-L_1_0_1-W_0_5_0_1-IPC_B|ModelDatafileKind0=PCBLib|DatalinksLocked=T|DatabaseDatalinksLocked=T
|RECORD=46|OwnerIndex=1310
|RECORD=48|OwnerIndex=1310
|RECORD=45|OwnerIndex=1306|IndexInSheet=-1|UseComponentLibrary=T|ModelName=FP-0402-L_1_0_1-W_0_5_0_1-MFG|ModelType=PCBLIB|DatafileCount=1|ModelDatafileEntity0=FP-0402-L_1_0_1-W_0_5_0_1-MFG|ModelDatafileKind0=PCBLib|DatalinksLocked=T|DatabaseDatalinksLocked=T
|RECORD=46|OwnerIndex=1313
|RECORD=48|OwnerIndex=1313
|RECORD=45|OwnerIndex=1306|IndexInSheet=-1|UseComponentLibrary=T|ModelName=FP-0402-L_1_0_1-W_0_5_0_1-IPC_A|ModelType=PCBLIB|DatafileCount=1|ModelDatafileEntity0=FP-0402-L_1_0_1-W_0_5_0_1-IPC_A|ModelDatafileKind0=PCBLib|DatalinksLocked=T|DatabaseDatalinksLocked=T
|RECORD=46|OwnerIndex=1316
|RECORD=48|OwnerIndex=1316
|RECORD=27|IndexInSheet=194|OwnerPartId=-1|LineWidth=1|Color=8388608|LocationCount=2|X1=1094|Y1=487|X2=1094|Y2=507
|RECORD=1|LibReference=b4654b650e69147ec39a6b967a45e02|ComponentDescription=General Purpose Ceramic Capacitor, 0402, 100nF, 10%, X7R, 15%, 25V|PartCount=2|DisplayModeCount=1|IndexInSheet=195|OwnerPartId=-1|Location.X=334|Location.Y=517|CurrentPartId=1|LibraryPath=*|SourceLibraryName=Altium Content Vault|TargetFileName=*|AreaColor=11599871|Color=128|PartIDLocked=T|DesignItemId=CMP-2008-02519-2|AllPinCount=2
|RECORD=2|OwnerIndex=1320|OwnerPartId=1|Electrical=4|PinConglomerate=49|PinLength=7|Location.X=334|Location.Y=510|Name=1|Designator=1|PinPropagationDelay=0.000000E+000
|RECORD=2|OwnerIndex=1320|OwnerPartId=1|Electrical=4|PinConglomerate=51|PinLength=6|Location.X=334|Location.Y=503|Name=2|Designator=2|PinPropagationDelay=0.000000E+000
|RECORD=13|OwnerIndex=1320|IsNotAccesible=T|IndexInSheet=2|OwnerPartId=1|Location.X=344|Location.Y=510|Corner.X=324|Corner.Y=510|LineWidth=1|Color=16711680
|RECORD=13|OwnerIndex=1320|IsNotAccesible=T|IndexInSheet=3|OwnerPartId=1|Location.X=344|Location.Y=504|Corner.X=324|Corner.Y=504|LineWidth=1|Color=16711680
|RECORD=13|OwnerIndex=1320|IsNotAccesible=T|IndexInSheet=4|OwnerPartId=1|Location.X=334|Location.Y=510|Corner.X=334|Corner.Y=513|LineWidth=1|Color=16711680
|RECORD=13|OwnerIndex=1320|IsNotAccesible=T|IndexInSheet=5|OwnerPartId=1|Location.X=334|Location.Y=503|Corner.X=334|Corner.Y=502|LineWidth=1|Color=16711680
|RECORD=41|OwnerIndex=1320|IndexInSheet=6|OwnerPartId=-1|Location.X=323|Location.Y=519|Color=8388608|FontID=1|IsHidden=T|Text=1|Name=Package Quantity
|RECORD=41|OwnerIndex=1320|IndexInSheet=7|OwnerPartId=-1|Location.X=323|Location.Y=519|Color=8388608|FontID=1|IsHidden=T|Text=100nF|Name=Capacitance
|RECORD=41|OwnerIndex=1320|IndexInSheet=8|OwnerPartId=-1|Location.X=323|Location.Y=519|Color=8388608|FontID=1|IsHidden=T|Text=-55°C|Name=Min Operating Temperature
|RECORD=41|OwnerIndex=1320|IndexInSheet=9|OwnerPartId=-1|Location.X=323|Location.Y=519|Color=8388608|FontID=1|IsHidden=T|Text=25V|Name=Voltage
|RECORD=41|OwnerIndex=1320|IndexInSheet=10|OwnerPartId=-1|Location.X=323|Location.Y=519|Color=8388608|FontID=1|IsHidden=T|Text=25V|Name=Voltage Rating
|RECORD=41|OwnerIndex=1320|IndexInSheet=11|OwnerPartId=-1|Location.X=323|Location.Y=519|Color=8388608|FontID=1|IsHidden=T|Text=Flat|Name=Construction
|RECORD=41|OwnerIndex=1320|IndexInSheet=12|OwnerPartId=-1|Location.X=323|Location.Y=519|Color=8388608|FontID=1|IsHidden=T|Text=125°C|Name=Max Operating Temperature
|RECORD=41|OwnerIndex=1320|IndexInSheet=13|OwnerPartId=-1|Location.X=323|Location.Y=519|Color=8388608|FontID=1|IsHidden=T|Text=No|Name=Radiation Hardening
|RECORD=41|OwnerIndex=1320|IndexInSheet=14|OwnerPartId=-1|Location.X=323|Location.Y=519|Color=8388608|FontID=1|IsHidden=T|Text=0.5mm|Name=Depth
|RECORD=41|OwnerIndex=1320|IndexInSheet=15|OwnerPartId=-1|Location.X=323|Location.Y=519|Color=8388608|FontID=1|IsHidden=T|Text=0.022inch|Name=Thickness
|RECORD=41|OwnerIndex=1320|IndexInSheet=16|OwnerPartId=-1|Location.X=323|Location.Y=519|Color=8388608|FontID=1|IsHidden=T|Text=25V|Name=Voltage Rating (DC)
|RECORD=41|OwnerIndex=1320|IndexInSheet=17|OwnerPartId=-1|Location.X=323|Location.Y=519|Color=8388608|FontID=1|IsHidden=T|Text=2|Name=Number of Pins
|RECORD=41|OwnerIndex=1320|IndexInSheet=18|OwnerPartId=-1|Location.X=323|Location.Y=519|Color=8388608|FontID=1|IsHidden=T|Text=Lead Free|Name=Lead Free
|RECORD=41|OwnerIndex=1320|IndexInSheet=19|OwnerPartId=-1|Location.X=323|Location.Y=519|Color=8388608|FontID=1|IsHidden=T|Text=-|Name=Series
|RECORD=41|OwnerIndex=1320|IndexInSheet=20|OwnerPartId=-1|Location.X=323|Location.Y=519|Color=8388608|FontID=1|IsHidden=T|Text=No SVHC|Name=REACH SVHC
|RECORD=41|OwnerIndex=1320|IndexInSheet=21|OwnerPartId=-1|Location.X=323|Location.Y=519|Color=8388608|FontID=1|IsHidden=T|Text=1mm|Name=Length
|RECORD=41|OwnerIndex=1320|IndexInSheet=22|OwnerPartId=-1|Location.X=323|Location.Y=519|Color=8388608|FontID=1|IsHidden=T|Text=X7R|Name=Dielectric
|RECORD=41|OwnerIndex=1320|IndexInSheet=23|OwnerPartId=-1|Location.X=323|Location.Y=519|Color=8388608|FontID=1|IsHidden=T|Text=Yes|Name=RoHS Compliant
|RECORD=41|OwnerIndex=1320|IndexInSheet=24|OwnerPartId=-1|Location.X=323|Location.Y=519|Color=8388608|FontID=1|IsHidden=T|Text=Surface Mount|Name=Mount
|RECORD=41|OwnerIndex=1320|IndexInSheet=25|OwnerPartId=-1|Location.X=323|Location.Y=519|Color=8388608|FontID=1|IsHidden=T|Text=Tape and Reel|Name=Packaging
|RECORD=41|OwnerIndex=1320|IndexInSheet=26|OwnerPartId=-1|Location.X=323|Location.Y=519|Color=8388608|FontID=1|IsHidden=T|Text=0402|Name=Case/Package
|RECORD=41|OwnerIndex=1320|IndexInSheet=27|OwnerPartId=-1|Location.X=323|Location.Y=519|Color=8388608|FontID=1|IsHidden=T|Text=0402|Name=Case Code (Imperial)
|RECORD=41|OwnerIndex=1320|IndexInSheet=28|OwnerPartId=-1|Location.X=323|Location.Y=519|Color=8388608|FontID=1|IsHidden=T|Text=SMD/SMT|Name=Termination
|RECORD=41|OwnerIndex=1320|IndexInSheet=29|OwnerPartId=-1|Location.X=323|Location.Y=519|Color=8388608|FontID=1|IsHidden=T|Text=0.02inch|Name=Width
|RECORD=41|OwnerIndex=1320|IndexInSheet=30|OwnerPartId=-1|Location.X=323|Location.Y=519|Color=8388608|FontID=1|IsHidden=T|Text=1005|Name=Case Code (Metric)
|RECORD=41|OwnerIndex=1320|IndexInSheet=31|OwnerPartId=-1|Location.X=323|Location.Y=519|Color=8388608|FontID=1|IsHidden=T|Text=10%|Name=Tolerance
|RECORD=34|OwnerIndex=1320|IndexInSheet=-1|OwnerPartId=-1|Location.X=324|Location.Y=497|Orientation=1|Color=8388608|FontID=2|Text=C29|Name=Designator|ReadOnlyState=1
|RECORD=41|OwnerIndex=1320|IndexInSheet=-1|OwnerPartId=1|Location.X=354|Location.Y=482|Orientation=1|Color=8388608|FontID=2|Text=0.1uF_25V_0402|Name=Comment
|RECORD=44|OwnerIndex=1320
|RECORD=45|OwnerIndex=1357|IndexInSheet=-1|UseComponentLibrary=T|ModelName=FP-0402-L_1_0_1-W_0_5_0_1-IPC_C|ModelType=PCBLIB|DatafileCount=1|ModelDatafileEntity0=FP-0402-L_1_0_1-W_0_5_0_1-IPC_C|ModelDatafileKind0=PCBLib|IsCurrent=T|DatalinksLocked=T|DatabaseDatalinksLocked=T
|RECORD=46|OwnerIndex=1358
|RECORD=48|OwnerIndex=1358
|RECORD=45|OwnerIndex=1357|IndexInSheet=-1|UseComponentLibrary=T|ModelName=FP-0402-L_1_0_1-W_0_5_0_1-IPC_B|ModelType=PCBLIB|DatafileCount=1|ModelDatafileEntity0=FP-0402-L_1_0_1-W_0_5_0_1-IPC_B|ModelDatafileKind0=PCBLib|DatalinksLocked=T|DatabaseDatalinksLocked=T
|RECORD=46|OwnerIndex=1361
|RECORD=48|OwnerIndex=1361
|RECORD=45|OwnerIndex=1357|IndexInSheet=-1|UseComponentLibrary=T|ModelName=FP-0402-L_1_0_1-W_0_5_0_1-MFG|ModelType=PCBLIB|DatafileCount=1|ModelDatafileEntity0=FP-0402-L_1_0_1-W_0_5_0_1-MFG|ModelDatafileKind0=PCBLib|DatalinksLocked=T|DatabaseDatalinksLocked=T
|RECORD=46|OwnerIndex=1364
|RECORD=48|OwnerIndex=1364
|RECORD=45|OwnerIndex=1357|IndexInSheet=-1|UseComponentLibrary=T|ModelName=FP-0402-L_1_0_1-W_0_5_0_1-IPC_A|ModelType=PCBLIB|DatafileCount=1|ModelDatafileEntity0=FP-0402-L_1_0_1-W_0_5_0_1-IPC_A|ModelDatafileKind0=PCBLib|DatalinksLocked=T|DatabaseDatalinksLocked=T
|RECORD=46|OwnerIndex=1367
|RECORD=48|OwnerIndex=1367
|RECORD=27|IndexInSheet=196|OwnerPartId=-1|LineWidth=1|Color=8388608|LocationCount=3|X1=334|Y1=517|X2=334|Y2=542|X3=394|Y3=542
|RECORD=1|LibReference=b4654b650e69147ec39a6b967a45e02|ComponentDescription=General Purpose Ceramic Capacitor, 0402, 100nF, 10%, X7R, 15%, 25V|PartCount=2|DisplayModeCount=1|IndexInSheet=197|OwnerPartId=-1|Location.X=334|Location.Y=847|CurrentPartId=1|LibraryPath=*|SourceLibraryName=Altium Content Vault|TargetFileName=*|AreaColor=11599871|Color=128|PartIDLocked=T|DesignItemId=CMP-2008-02519-2|AllPinCount=2
|RECORD=2|OwnerIndex=1371|OwnerPartId=1|Electrical=4|PinConglomerate=49|PinLength=7|Location.X=334|Location.Y=840|Name=1|Designator=1|PinPropagationDelay=0.000000E+000
|RECORD=2|OwnerIndex=1371|OwnerPartId=1|Electrical=4|PinConglomerate=51|PinLength=6|Location.X=334|Location.Y=833|Name=2|Designator=2|PinPropagationDelay=0.000000E+000
|RECORD=13|OwnerIndex=1371|IsNotAccesible=T|IndexInSheet=2|OwnerPartId=1|Location.X=344|Location.Y=840|Corner.X=324|Corner.Y=840|LineWidth=1|Color=16711680
|RECORD=13|OwnerIndex=1371|IsNotAccesible=T|IndexInSheet=3|OwnerPartId=1|Location.X=344|Location.Y=834|Corner.X=324|Corner.Y=834|LineWidth=1|Color=16711680
|RECORD=13|OwnerIndex=1371|IsNotAccesible=T|IndexInSheet=4|OwnerPartId=1|Location.X=334|Location.Y=840|Corner.X=334|Corner.Y=843|LineWidth=1|Color=16711680
|RECORD=13|OwnerIndex=1371|IsNotAccesible=T|IndexInSheet=5|OwnerPartId=1|Location.X=334|Location.Y=833|Corner.X=334|Corner.Y=832|LineWidth=1|Color=16711680
|RECORD=41|OwnerIndex=1371|IndexInSheet=6|OwnerPartId=-1|Location.X=323|Location.Y=849|Color=8388608|FontID=1|IsHidden=T|Text=1|Name=Package Quantity
|RECORD=41|OwnerIndex=1371|IndexInSheet=7|OwnerPartId=-1|Location.X=323|Location.Y=849|Color=8388608|FontID=1|IsHidden=T|Text=100nF|Name=Capacitance
|RECORD=41|OwnerIndex=1371|IndexInSheet=8|OwnerPartId=-1|Location.X=323|Location.Y=849|Color=8388608|FontID=1|IsHidden=T|Text=-55°C|Name=Min Operating Temperature
|RECORD=41|OwnerIndex=1371|IndexInSheet=9|OwnerPartId=-1|Location.X=323|Location.Y=849|Color=8388608|FontID=1|IsHidden=T|Text=25V|Name=Voltage
|RECORD=41|OwnerIndex=1371|IndexInSheet=10|OwnerPartId=-1|Location.X=323|Location.Y=849|Color=8388608|FontID=1|IsHidden=T|Text=25V|Name=Voltage Rating
|RECORD=41|OwnerIndex=1371|IndexInSheet=11|OwnerPartId=-1|Location.X=323|Location.Y=849|Color=8388608|FontID=1|IsHidden=T|Text=Flat|Name=Construction
|RECORD=41|OwnerIndex=1371|IndexInSheet=12|OwnerPartId=-1|Location.X=323|Location.Y=849|Color=8388608|FontID=1|IsHidden=T|Text=125°C|Name=Max Operating Temperature
|RECORD=41|OwnerIndex=1371|IndexInSheet=13|OwnerPartId=-1|Location.X=323|Location.Y=849|Color=8388608|FontID=1|IsHidden=T|Text=No|Name=Radiation Hardening
|RECORD=41|OwnerIndex=1371|IndexInSheet=14|OwnerPartId=-1|Location.X=323|Location.Y=849|Color=8388608|FontID=1|IsHidden=T|Text=0.5mm|Name=Depth
|RECORD=41|OwnerIndex=1371|IndexInSheet=15|OwnerPartId=-1|Location.X=323|Location.Y=849|Color=8388608|FontID=1|IsHidden=T|Text=0.022inch|Name=Thickness
|RECORD=41|OwnerIndex=1371|IndexInSheet=16|OwnerPartId=-1|Location.X=323|Location.Y=849|Color=8388608|FontID=1|IsHidden=T|Text=25V|Name=Voltage Rating (DC)
|RECORD=41|OwnerIndex=1371|IndexInSheet=17|OwnerPartId=-1|Location.X=323|Location.Y=849|Color=8388608|FontID=1|IsHidden=T|Text=2|Name=Number of Pins
|RECORD=41|OwnerIndex=1371|IndexInSheet=18|OwnerPartId=-1|Location.X=323|Location.Y=849|Color=8388608|FontID=1|IsHidden=T|Text=Lead Free|Name=Lead Free
|RECORD=41|OwnerIndex=1371|IndexInSheet=19|OwnerPartId=-1|Location.X=323|Location.Y=849|Color=8388608|FontID=1|IsHidden=T|Text=-|Name=Series
|RECORD=41|OwnerIndex=1371|IndexInSheet=20|OwnerPartId=-1|Location.X=323|Location.Y=849|Color=8388608|FontID=1|IsHidden=T|Text=No SVHC|Name=REACH SVHC
|RECORD=41|OwnerIndex=1371|IndexInSheet=21|OwnerPartId=-1|Location.X=323|Location.Y=849|Color=8388608|FontID=1|IsHidden=T|Text=1mm|Name=Length
|RECORD=41|OwnerIndex=1371|IndexInSheet=22|OwnerPartId=-1|Location.X=323|Location.Y=849|Color=8388608|FontID=1|IsHidden=T|Text=X7R|Name=Dielectric
|RECORD=41|OwnerIndex=1371|IndexInSheet=23|OwnerPartId=-1|Location.X=323|Location.Y=849|Color=8388608|FontID=1|IsHidden=T|Text=Yes|Name=RoHS Compliant
|RECORD=41|OwnerIndex=1371|IndexInSheet=24|OwnerPartId=-1|Location.X=323|Location.Y=849|Color=8388608|FontID=1|IsHidden=T|Text=Surface Mount|Name=Mount
|RECORD=41|OwnerIndex=1371|IndexInSheet=25|OwnerPartId=-1|Location.X=323|Location.Y=849|Color=8388608|FontID=1|IsHidden=T|Text=Tape and Reel|Name=Packaging
|RECORD=41|OwnerIndex=1371|IndexInSheet=26|OwnerPartId=-1|Location.X=323|Location.Y=849|Color=8388608|FontID=1|IsHidden=T|Text=0402|Name=Case/Package
|RECORD=41|OwnerIndex=1371|IndexInSheet=27|OwnerPartId=-1|Location.X=323|Location.Y=849|Color=8388608|FontID=1|IsHidden=T|Text=0402|Name=Case Code (Imperial)
|RECORD=41|OwnerIndex=1371|IndexInSheet=28|OwnerPartId=-1|Location.X=323|Location.Y=849|Color=8388608|FontID=1|IsHidden=T|Text=SMD/SMT|Name=Termination
|RECORD=41|OwnerIndex=1371|IndexInSheet=29|OwnerPartId=-1|Location.X=323|Location.Y=849|Color=8388608|FontID=1|IsHidden=T|Text=0.02inch|Name=Width
|RECORD=41|OwnerIndex=1371|IndexInSheet=30|OwnerPartId=-1|Location.X=323|Location.Y=849|Color=8388608|FontID=1|IsHidden=T|Text=1005|Name=Case Code (Metric)
|RECORD=41|OwnerIndex=1371|IndexInSheet=31|OwnerPartId=-1|Location.X=323|Location.Y=849|Color=8388608|FontID=1|IsHidden=T|Text=10%|Name=Tolerance
|RECORD=34|OwnerIndex=1371|IndexInSheet=-1|OwnerPartId=-1|Location.X=324|Location.Y=827|Orientation=1|Color=8388608|FontID=2|Text=C26|Name=Designator|ReadOnlyState=1
|RECORD=41|OwnerIndex=1371|IndexInSheet=-1|OwnerPartId=1|Location.X=354|Location.Y=812|Orientation=1|Color=8388608|FontID=2|Text=0.1uF_25V_0402|Name=Comment
|RECORD=44|OwnerIndex=1371
|RECORD=45|OwnerIndex=1408|IndexInSheet=-1|UseComponentLibrary=T|ModelName=FP-0402-L_1_0_1-W_0_5_0_1-IPC_C|ModelType=PCBLIB|DatafileCount=1|ModelDatafileEntity0=FP-0402-L_1_0_1-W_0_5_0_1-IPC_C|ModelDatafileKind0=PCBLib|IsCurrent=T|DatalinksLocked=T|DatabaseDatalinksLocked=T
|RECORD=46|OwnerIndex=1409
|RECORD=48|OwnerIndex=1409
|RECORD=45|OwnerIndex=1408|IndexInSheet=-1|UseComponentLibrary=T|ModelName=FP-0402-L_1_0_1-W_0_5_0_1-IPC_B|ModelType=PCBLIB|DatafileCount=1|ModelDatafileEntity0=FP-0402-L_1_0_1-W_0_5_0_1-IPC_B|ModelDatafileKind0=PCBLib|DatalinksLocked=T|DatabaseDatalinksLocked=T
|RECORD=46|OwnerIndex=1412
|RECORD=48|OwnerIndex=1412
|RECORD=45|OwnerIndex=1408|IndexInSheet=-1|UseComponentLibrary=T|ModelName=FP-0402-L_1_0_1-W_0_5_0_1-MFG|ModelType=PCBLIB|DatafileCount=1|ModelDatafileEntity0=FP-0402-L_1_0_1-W_0_5_0_1-MFG|ModelDatafileKind0=PCBLib|DatalinksLocked=T|DatabaseDatalinksLocked=T
|RECORD=46|OwnerIndex=1415
|RECORD=48|OwnerIndex=1415
|RECORD=45|OwnerIndex=1408|IndexInSheet=-1|UseComponentLibrary=T|ModelName=FP-0402-L_1_0_1-W_0_5_0_1-IPC_A|ModelType=PCBLIB|DatafileCount=1|ModelDatafileEntity0=FP-0402-L_1_0_1-W_0_5_0_1-IPC_A|ModelDatafileKind0=PCBLib|DatalinksLocked=T|DatabaseDatalinksLocked=T
|RECORD=46|OwnerIndex=1418
|RECORD=48|OwnerIndex=1418
|RECORD=27|IndexInSheet=198|OwnerPartId=-1|LineWidth=1|Color=8388608|LocationCount=3|X1=334|Y1=847|X2=334|Y2=872|X3=394|Y3=872
|RECORD=1|LibReference=b4654b650e69147ec39a6b967a45e02|ComponentDescription=General Purpose Ceramic Capacitor, 0402, 100nF, 10%, X7R, 15%, 25V|PartCount=2|DisplayModeCount=1|IndexInSheet=199|OwnerPartId=-1|Location.X=1094|Location.Y=847|CurrentPartId=1|LibraryPath=*|SourceLibraryName=Altium Content Vault|TargetFileName=*|AreaColor=11599871|Color=128|PartIDLocked=T|DesignItemId=CMP-2008-02519-2|AllPinCount=2
|RECORD=2|OwnerIndex=1422|OwnerPartId=1|Electrical=4|PinConglomerate=49|PinLength=7|Location.X=1094|Location.Y=840|Name=1|Designator=1|PinPropagationDelay=0.000000E+000
|RECORD=2|OwnerIndex=1422|OwnerPartId=1|Electrical=4|PinConglomerate=51|PinLength=6|Location.X=1094|Location.Y=833|Name=2|Designator=2|PinPropagationDelay=0.000000E+000
|RECORD=13|OwnerIndex=1422|IsNotAccesible=T|IndexInSheet=2|OwnerPartId=1|Location.X=1104|Location.Y=840|Corner.X=1084|Corner.Y=840|LineWidth=1|Color=16711680
|RECORD=13|OwnerIndex=1422|IsNotAccesible=T|IndexInSheet=3|OwnerPartId=1|Location.X=1104|Location.Y=834|Corner.X=1084|Corner.Y=834|LineWidth=1|Color=16711680
|RECORD=13|OwnerIndex=1422|IsNotAccesible=T|IndexInSheet=4|OwnerPartId=1|Location.X=1094|Location.Y=840|Corner.X=1094|Corner.Y=843|LineWidth=1|Color=16711680
|RECORD=13|OwnerIndex=1422|IsNotAccesible=T|IndexInSheet=5|OwnerPartId=1|Location.X=1094|Location.Y=833|Corner.X=1094|Corner.Y=832|LineWidth=1|Color=16711680
|RECORD=41|OwnerIndex=1422|IndexInSheet=6|OwnerPartId=-1|Location.X=1083|Location.Y=849|Color=8388608|FontID=1|IsHidden=T|Text=1|Name=Package Quantity
|RECORD=41|OwnerIndex=1422|IndexInSheet=7|OwnerPartId=-1|Location.X=1083|Location.Y=849|Color=8388608|FontID=1|IsHidden=T|Text=100nF|Name=Capacitance
|RECORD=41|OwnerIndex=1422|IndexInSheet=8|OwnerPartId=-1|Location.X=1083|Location.Y=849|Color=8388608|FontID=1|IsHidden=T|Text=-55°C|Name=Min Operating Temperature
|RECORD=41|OwnerIndex=1422|IndexInSheet=9|OwnerPartId=-1|Location.X=1083|Location.Y=849|Color=8388608|FontID=1|IsHidden=T|Text=25V|Name=Voltage
|RECORD=41|OwnerIndex=1422|IndexInSheet=10|OwnerPartId=-1|Location.X=1083|Location.Y=849|Color=8388608|FontID=1|IsHidden=T|Text=25V|Name=Voltage Rating
|RECORD=41|OwnerIndex=1422|IndexInSheet=11|OwnerPartId=-1|Location.X=1083|Location.Y=849|Color=8388608|FontID=1|IsHidden=T|Text=Flat|Name=Construction
|RECORD=41|OwnerIndex=1422|IndexInSheet=12|OwnerPartId=-1|Location.X=1083|Location.Y=849|Color=8388608|FontID=1|IsHidden=T|Text=125°C|Name=Max Operating Temperature
|RECORD=41|OwnerIndex=1422|IndexInSheet=13|OwnerPartId=-1|Location.X=1083|Location.Y=849|Color=8388608|FontID=1|IsHidden=T|Text=No|Name=Radiation Hardening
|RECORD=41|OwnerIndex=1422|IndexInSheet=14|OwnerPartId=-1|Location.X=1083|Location.Y=849|Color=8388608|FontID=1|IsHidden=T|Text=0.5mm|Name=Depth
|RECORD=41|OwnerIndex=1422|IndexInSheet=15|OwnerPartId=-1|Location.X=1083|Location.Y=849|Color=8388608|FontID=1|IsHidden=T|Text=0.022inch|Name=Thickness
|RECORD=41|OwnerIndex=1422|IndexInSheet=16|OwnerPartId=-1|Location.X=1083|Location.Y=849|Color=8388608|FontID=1|IsHidden=T|Text=25V|Name=Voltage Rating (DC)
|RECORD=41|OwnerIndex=1422|IndexInSheet=17|OwnerPartId=-1|Location.X=1083|Location.Y=849|Color=8388608|FontID=1|IsHidden=T|Text=2|Name=Number of Pins
|RECORD=41|OwnerIndex=1422|IndexInSheet=18|OwnerPartId=-1|Location.X=1083|Location.Y=849|Color=8388608|FontID=1|IsHidden=T|Text=Lead Free|Name=Lead Free
|RECORD=41|OwnerIndex=1422|IndexInSheet=19|OwnerPartId=-1|Location.X=1083|Location.Y=849|Color=8388608|FontID=1|IsHidden=T|Text=-|Name=Series
|RECORD=41|OwnerIndex=1422|IndexInSheet=20|OwnerPartId=-1|Location.X=1083|Location.Y=849|Color=8388608|FontID=1|IsHidden=T|Text=No SVHC|Name=REACH SVHC
|RECORD=41|OwnerIndex=1422|IndexInSheet=21|OwnerPartId=-1|Location.X=1083|Location.Y=849|Color=8388608|FontID=1|IsHidden=T|Text=1mm|Name=Length
|RECORD=41|OwnerIndex=1422|IndexInSheet=22|OwnerPartId=-1|Location.X=1083|Location.Y=849|Color=8388608|FontID=1|IsHidden=T|Text=X7R|Name=Dielectric
|RECORD=41|OwnerIndex=1422|IndexInSheet=23|OwnerPartId=-1|Location.X=1083|Location.Y=849|Color=8388608|FontID=1|IsHidden=T|Text=Yes|Name=RoHS Compliant
|RECORD=41|OwnerIndex=1422|IndexInSheet=24|OwnerPartId=-1|Location.X=1083|Location.Y=849|Color=8388608|FontID=1|IsHidden=T|Text=Surface Mount|Name=Mount
|RECORD=41|OwnerIndex=1422|IndexInSheet=25|OwnerPartId=-1|Location.X=1083|Location.Y=849|Color=8388608|FontID=1|IsHidden=T|Text=Tape and Reel|Name=Packaging
|RECORD=41|OwnerIndex=1422|IndexInSheet=26|OwnerPartId=-1|Location.X=1083|Location.Y=849|Color=8388608|FontID=1|IsHidden=T|Text=0402|Name=Case/Package
|RECORD=41|OwnerIndex=1422|IndexInSheet=27|OwnerPartId=-1|Location.X=1083|Location.Y=849|Color=8388608|FontID=1|IsHidden=T|Text=0402|Name=Case Code (Imperial)
|RECORD=41|OwnerIndex=1422|IndexInSheet=28|OwnerPartId=-1|Location.X=1083|Location.Y=849|Color=8388608|FontID=1|IsHidden=T|Text=SMD/SMT|Name=Termination
|RECORD=41|OwnerIndex=1422|IndexInSheet=29|OwnerPartId=-1|Location.X=1083|Location.Y=849|Color=8388608|FontID=1|IsHidden=T|Text=0.02inch|Name=Width
|RECORD=41|OwnerIndex=1422|IndexInSheet=30|OwnerPartId=-1|Location.X=1083|Location.Y=849|Color=8388608|FontID=1|IsHidden=T|Text=1005|Name=Case Code (Metric)
|RECORD=41|OwnerIndex=1422|IndexInSheet=31|OwnerPartId=-1|Location.X=1083|Location.Y=849|Color=8388608|FontID=1|IsHidden=T|Text=10%|Name=Tolerance
|RECORD=34|OwnerIndex=1422|IndexInSheet=-1|OwnerPartId=-1|Location.X=1084|Location.Y=827|Orientation=1|Color=8388608|FontID=2|Text=C27|Name=Designator|ReadOnlyState=1
|RECORD=41|OwnerIndex=1422|IndexInSheet=-1|OwnerPartId=1|Location.X=1114|Location.Y=812|Orientation=1|Color=8388608|FontID=2|Text=0.1uF_25V_0402|Name=Comment
|RECORD=44|OwnerIndex=1422
|RECORD=45|OwnerIndex=1459|IndexInSheet=-1|UseComponentLibrary=T|ModelName=FP-0402-L_1_0_1-W_0_5_0_1-IPC_C|ModelType=PCBLIB|DatafileCount=1|ModelDatafileEntity0=FP-0402-L_1_0_1-W_0_5_0_1-IPC_C|ModelDatafileKind0=PCBLib|IsCurrent=T|DatalinksLocked=T|DatabaseDatalinksLocked=T
|RECORD=46|OwnerIndex=1460
|RECORD=48|OwnerIndex=1460
|RECORD=45|OwnerIndex=1459|IndexInSheet=-1|UseComponentLibrary=T|ModelName=FP-0402-L_1_0_1-W_0_5_0_1-IPC_B|ModelType=PCBLIB|DatafileCount=1|ModelDatafileEntity0=FP-0402-L_1_0_1-W_0_5_0_1-IPC_B|ModelDatafileKind0=PCBLib|DatalinksLocked=T|DatabaseDatalinksLocked=T
|RECORD=46|OwnerIndex=1463
|RECORD=48|OwnerIndex=1463
|RECORD=45|OwnerIndex=1459|IndexInSheet=-1|UseComponentLibrary=T|ModelName=FP-0402-L_1_0_1-W_0_5_0_1-MFG|ModelType=PCBLIB|DatafileCount=1|ModelDatafileEntity0=FP-0402-L_1_0_1-W_0_5_0_1-MFG|ModelDatafileKind0=PCBLib|DatalinksLocked=T|DatabaseDatalinksLocked=T
|RECORD=46|OwnerIndex=1466
|RECORD=48|OwnerIndex=1466
|RECORD=45|OwnerIndex=1459|IndexInSheet=-1|UseComponentLibrary=T|ModelName=FP-0402-L_1_0_1-W_0_5_0_1-IPC_A|ModelType=PCBLIB|DatafileCount=1|ModelDatafileEntity0=FP-0402-L_1_0_1-W_0_5_0_1-IPC_A|ModelDatafileKind0=PCBLib|DatalinksLocked=T|DatabaseDatalinksLocked=T
|RECORD=46|OwnerIndex=1469
|RECORD=48|OwnerIndex=1469
|RECORD=27|IndexInSheet=200|OwnerPartId=-1|LineWidth=1|Color=8388608|LocationCount=3|X1=1094|Y1=847|X2=1094|Y2=872|X3=1154|Y3=872
|RECORD=27|IndexInSheet=201|OwnerPartId=-1|LineWidth=1|Color=8388608|LocationCount=3|X1=569|Y1=947|X2=594|Y2=947|X3=594|Y3=867
|RECORD=27|IndexInSheet=202|OwnerPartId=-1|LineWidth=1|Color=8388608|LocationCount=2|X1=594|Y1=947|X2=624|Y2=947
|RECORD=27|IndexInSheet=203|OwnerPartId=-1|LineWidth=1|Color=8388608|LocationCount=2|X1=569|Y1=617|X2=594|Y2=617
|RECORD=27|IndexInSheet=204|OwnerPartId=-1|LineWidth=1|Color=8388608|LocationCount=2|X1=594|Y1=617|X2=624|Y2=617
|RECORD=27|IndexInSheet=205|OwnerPartId=-1|LineWidth=1|Color=8388608|LocationCount=2|X1=270|Y1=970|X2=270|Y2=1000
|RECORD=27|IndexInSheet=206|OwnerPartId=-1|LineWidth=1|Color=8388608|LocationCount=3|X1=1329|Y1=947|X2=1354|Y2=947|X3=1354|Y3=867
|RECORD=27|IndexInSheet=207|OwnerPartId=-1|LineWidth=1|Color=8388608|LocationCount=2|X1=1384|Y1=947|X2=1354|Y2=947
|RECORD=29|IndexInSheet=-1|OwnerPartId=-1|Location.X=270|Location.Y=642|Color=128
|RECORD=29|IndexInSheet=-1|OwnerPartId=-1|Location.X=270|Location.Y=970|Color=128
|RECORD=29|IndexInSheet=-1|OwnerPartId=-1|Location.X=300|Location.Y=587|Color=128
|RECORD=29|IndexInSheet=-1|OwnerPartId=-1|Location.X=300|Location.Y=920|Color=128
|RECORD=29|IndexInSheet=-1|OwnerPartId=-1|Location.X=334|Location.Y=542|Color=128
|RECORD=29|IndexInSheet=-1|OwnerPartId=-1|Location.X=334|Location.Y=872|Color=128
|RECORD=29|IndexInSheet=-1|OwnerPartId=-1|Location.X=514|Location.Y=617|Color=128
|RECORD=29|IndexInSheet=-1|OwnerPartId=-1|Location.X=514|Location.Y=947|Color=128
|RECORD=29|IndexInSheet=-1|OwnerPartId=-1|Location.X=594|Location.Y=617|Color=128
|RECORD=29|IndexInSheet=-1|OwnerPartId=-1|Location.X=594|Location.Y=867|Color=128
|RECORD=29|IndexInSheet=-1|OwnerPartId=-1|Location.X=594|Location.Y=947|Color=128
|RECORD=29|IndexInSheet=-1|OwnerPartId=-1|Location.X=654|Location.Y=492|Color=128
|RECORD=29|IndexInSheet=-1|OwnerPartId=-1|Location.X=654|Location.Y=822|Color=128
|RECORD=29|IndexInSheet=-1|OwnerPartId=-1|Location.X=664|Location.Y=492|Color=128
|RECORD=29|IndexInSheet=-1|OwnerPartId=-1|Location.X=664|Location.Y=587|Color=128
|RECORD=29|IndexInSheet=-1|OwnerPartId=-1|Location.X=664|Location.Y=822|Color=128
|RECORD=29|IndexInSheet=-1|OwnerPartId=-1|Location.X=664|Location.Y=917|Color=128
|RECORD=29|IndexInSheet=-1|OwnerPartId=-1|Location.X=674|Location.Y=492|Color=128
|RECORD=29|IndexInSheet=-1|OwnerPartId=-1|Location.X=674|Location.Y=822|Color=128
|RECORD=29|IndexInSheet=-1|OwnerPartId=-1|Location.X=1030|Location.Y=642|Color=128
|RECORD=29|IndexInSheet=-1|OwnerPartId=-1|Location.X=1030|Location.Y=970|Color=128
|RECORD=29|IndexInSheet=-1|OwnerPartId=-1|Location.X=1060|Location.Y=587|Color=128
|RECORD=29|IndexInSheet=-1|OwnerPartId=-1|Location.X=1060|Location.Y=917|Color=128
|RECORD=29|IndexInSheet=-1|OwnerPartId=-1|Location.X=1094|Location.Y=542|Color=128
|RECORD=29|IndexInSheet=-1|OwnerPartId=-1|Location.X=1094|Location.Y=872|Color=128
|RECORD=29|IndexInSheet=-1|OwnerPartId=-1|Location.X=1274|Location.Y=617|Color=128
|RECORD=29|IndexInSheet=-1|OwnerPartId=-1|Location.X=1274|Location.Y=947|Color=128
|RECORD=29|IndexInSheet=-1|OwnerPartId=-1|Location.X=1354|Location.Y=617|Color=128
|RECORD=29|IndexInSheet=-1|OwnerPartId=-1|Location.X=1354|Location.Y=867|Color=128
|RECORD=29|IndexInSheet=-1|OwnerPartId=-1|Location.X=1354|Location.Y=947|Color=128
|RECORD=29|IndexInSheet=-1|OwnerPartId=-1|Location.X=1414|Location.Y=492|Color=128
|RECORD=29|IndexInSheet=-1|OwnerPartId=-1|Location.X=1414|Location.Y=822|Color=128
|RECORD=29|IndexInSheet=-1|OwnerPartId=-1|Location.X=1424|Location.Y=492|Color=128
|RECORD=29|IndexInSheet=-1|OwnerPartId=-1|Location.X=1424|Location.Y=587|Color=128
|RECORD=29|IndexInSheet=-1|OwnerPartId=-1|Location.X=1424|Location.Y=822|Color=128
|RECORD=29|IndexInSheet=-1|OwnerPartId=-1|Location.X=1424|Location.Y=917|Color=128
|RECORD=29|IndexInSheet=-1|OwnerPartId=-1|Location.X=1434|Location.Y=492|Color=128
|RECORD=29|IndexInSheet=-1|OwnerPartId=-1|Location.X=1434|Location.Y=822|Color=128